5
5
4
4
3
3
2
2
1
1
D D
C C
B B
A A
PAGE13:PCIE SLOTS x1 
PAGE16:P5VA for HDD 0-4 
PAGE15:P3V3_SY8201 
PAGE14:STRADDLE CONN 
PAGE17:P5VB for HDD 5-9 
PAGE20:CHANGE HISTORY_1 
PAGE19:SCREWS 
PAGE18:P5VC for HDD 10-14 
PAGE02:Power Map 
PAGE06:HDD CNs 6-7 
PAGE01:Block diagram 
PAGE03:HDD CNs 0-1 
PAGE04:HDD CNs 2-3 
PAGE05:HDD CNs 4-5 
PAGE07:HDD CNs 8-9 
PAGE08:HDD CNs 10-11 
PAGE09:HDD CNs 12-13 
PAGE10:HDD CNs 14 
PAGE11:I2C_B DEVICES 
PAGE12:PCIE SLOTS x16 
Revision Histroy: 
EVT-1 V09:2012/03/23 EVT Gerber Release 
EVT-3 V01:2012/04/19 EVT-3 Gerber Release 
DVT   V03: 2012/07/21 DVT Gerber Release 
PVT   VXX:2012/10/XX PVT Gerber Release 
Block Diagram 
36P24S 
Straddle 
P+S CONN 
x1 36P 
PCIe CONN 
x16 164P 
PCIe CONN 
x1 36P 
PCIe CONN 
x16 164P 
PCIe CONN 
SAS HDD 
CONNx15 
SAS x15 
SAS x15 
PRSNT DETECTION x15 
PWR CONTROL        x15 
FAULT LED CONTROLx15 
PRSNT DETECTION x15 
PWR CONTROL        x15 
FAULT LED CONTROLx15 
TMP SENSOR 
 TMP75 x4 
EEPROM 
 24C64 
VOLTAGE SENSOR 
ADS1015 
I2C_B BUS 
I2C_B BUS 
PAGE21:CHANGE HISTORY_2 
I2C_D BUS 
SAS x1 
Title 
Size Document Number Rev 
Date: Sheet 
of 
KNOX_DPB -1 
BLOCK DIAGRAM 
C
1 21 Thursday, October 11, 2012 
Wiwynn 
H/W R&D Dept. II 
8F,90,Sec. 1,Hsin Tai Wu Rd, 
Hsichih, Taipei Hsien 221, Taiwan, R.O.C 
Title 
Size Document Number Rev 
Date: Sheet 
of 
KNOX_DPB -1 
BLOCK DIAGRAM 
C
1 21 Thursday, October 11, 2012 
Wiwynn 
H/W R&D Dept. II 
8F,90,Sec. 1,Hsin Tai Wu Rd, 
Hsichih, Taipei Hsien 221, Taiwan, R.O.C 
Title 
Size Document Number Rev 
Date: Sheet 
of 
KNOX_DPB -1 
BLOCK DIAGRAM 
C
1 21 Thursday, October 11, 2012 
Wiwynn 
H/W R&D Dept. II 
8F,90,Sec. 1,Hsin Tai Wu Rd, 
Hsichih, Taipei Hsien 221, Taiwan, R.O.C 



5
5
4
4
3
3
2
2
1
1
D D
C C
B B
A A
55.64W03.D01G 
55.64W03.S01G 
48.64W03.0SA 
12432-SA 
PCIE CONN 
CN1 
POWER MAP 
(14.82A) 
 Power CONN 
PLA04F4BN0A1-AA 
Sheet 12 
HDD CNs 0~14 
DY=Dummy parts 
  =not populated 
EVT BUILD 
562R2F- GP 
562 = 562 ohm, (2K2R means 2.2K ohm) 
2 = size 0402 
F = 1% tolerance 
GP= Green Part (RoHS) 
Wistron RC size code as below: 
1 = 0201 
2= 0402 
3= 0603 
5= 0805 
6= 1206 
Wistron R tolerance code as below: 
D=0.5% 
F= 1% 
J= 5% 
SCD1U10V2KX-5GP 
D1U = 0.1uF (2D2U means 2.2uF) 
10Voltage (6D3V means 6.3V) 
2 = size 0402, K tolerance 
K=tolerance 
[Wistron C code as below:] 
G=2% 
J=5% 
K=10% 
M=20% 
X=temp characteristics 
[Wistron C Series/Temp] 
N=NPO 
X=X7R/X5R 
Y=Y5V 
-5=different symbol/customer 
GP= Green Part (RoHS) 
EEPROM 
P3V3 
(0.2A) 
 TEMP 
SENSOR 
U47 
U48 
U49 
DVT BUILD 
   U54 
  SY8021 
PCBA_DIP 
PCBA_SMT 
12V 
PCB P/N 
PCB VER 
CN4 
(1.392A*2) 
CN2 
Sheet 3~11 
HDD CNs 0~4 
LEDs 1~5 
U46 
   PU1 
 TPS53319 
(6.37A) 
HDD CNs 5~9 
   PU2 
 TPS53319 
HDD CNs 10~14 
   PU2 
 TPS53319 LEDs 6~10 LEDs 11~15 
U50 
U53 
  VOL 
SENSOR 
(6.37A) (6.37A) 
P5VA P5VB P5VC 
55.64W03.DA5G 
55.64W03.SA5G 
48.64W03.0SB 
EVT-3 BUILD 
12432-SB 12432-1A 
48.64W03.01A 
55.64W03.DA7G 
55.64W03.SA7G 
GCE 
Hannstar 
GCE 
Hannstar 
55.64W03.DA4G 
55.64W03.SA4G 
55.64W03.DA8G 
55.64W03.SA8G 
  PCB 
VENDOR 
GCE 
Hannstar 48.64W06.0SB 48.64W06.01A 
PVT BUILD 
12432-1 
Title 
Size Document Number Rev 
Date: Sheet 
of 
KNOX_DPB 
-1 
POWER MAP 
A3 
2 21 Thursday, October 11, 2012 
Wiwynn 
H/W R&D Dept. II 
8F,90,Sec. 1,Hsin Tai Wu Rd, 
Hsichih, Taipei Hsien 221, Taiwan, R.O.C 
Title 
Size Document Number Rev 
Date: Sheet 
of 
KNOX_DPB 
-1 
POWER MAP 
A3 
2 21 Thursday, October 11, 2012 
Wiwynn 
H/W R&D Dept. II 
8F,90,Sec. 1,Hsin Tai Wu Rd, 
Hsichih, Taipei Hsien 221, Taiwan, R.O.C 
Title 
Size Document Number Rev 
Date: Sheet 
of 
KNOX_DPB 
-1 
POWER MAP 
A3 
2 21 Thursday, October 11, 2012 
Wiwynn 
H/W R&D Dept. II 
8F,90,Sec. 1,Hsin Tai Wu Rd, 
Hsichih, Taipei Hsien 221, Taiwan, R.O.C 



5
5
4
4
3
3
2
2
1
1
D D
C C
B B
A A
BLUE VF=2.9V 
I=4.7mA 
ID=12A 
RDS(on) 
=11.5m ohm 
N-Channel 
P-Channel 
N-Channel 
P-Channel 
ID=-9A 
RDS(on) 
=20m ohm 
HDD0 
HDD1 
Ihold=2A 
Itrip=4A 
Ihold=3A 
Itrip=6A 
ID=12A 
RDS(on) 
=11.5m ohm 
ID=-9A 
RDS(on) 
=20m ohm 
EXP_A_HDD0_FLT EXP_B_HDD0_FLT 
0
0
1
1
0
0
1
1
HDD0_FLT_LED 
ON 
ON 
ON 
OFF 
1
1
0
0
1
1
HDD0_PWR EXP_A_PWR0 
OFF 
OFF 
OFF 
EXP_B_PWR0 
ON 
0
0
RED VF=1.8V 
I=4.5mA 
AND GATE 
AND GATE 
AND GATE 
AND GATE 
1
1
0
0
1
1
HDD1_PWR EXP_A_PWR1 
OFF 
OFF 
OFF 
EXP_B_PWR1 
ON 
0
0
1
1
0
0
1
1
HDD1_FLT_LED EXP_A_HDD1_FLT 
ON 
ON 
ON 
EXP_B_HDD1_FLT 
OFF 
0
0
Ihold=3A 
Itrip=6A 
Ihold=2A 
Itrip=4A 
EVT-3R 
20120620 
EVT-3R 
20120620 
DVT 
20120710 
DVT 
20120630 
DVT 
20120630 
BLUE VF=2.9V 
I=4.7mA 
DVT 
20120710 
RED VF=1.8V 
I=4.5mA 
DVT 
20120703 
DVT 
20120703 
DVT 
20120703 
DVT 
20120703 
DVT 
20120710 
DVT 
20120710 
DVT 
20120710 
DVT 
20120710 
DVT 
20120710 
DVT 
20120710 
DVT 
20120712 
DVT 
20120712 
DVT 
20120712 
DVT 
20120712 
DVT 
20120724 
DVT 
20120724 
PVT 
20121009 
PVT 
20121009 
PVT 
20121009 
PVT 
20121009 
SAS2x28_Drive_RX_N_A0 
SAS2x28_Drive_RX_P_A0 
SAS2x28_Drive_RX_N_B0 
SAS2x28_Drive_RX_P_B0 
5V_PRE_0 
12V_PRE_0 
DRV_ACT_NET0 
FLT_NET_HDD0 
FLT_NET_HDD1 
12V_PRE_1 
SAS2x28_Drive_RX_N_A1 
SAS2x28_Drive_RX_P_A1 
SAS2x28_Drive_RX_N_B1 
SAS2x28_Drive_RX_P_B1 
5V_PRE_1 
DRV_ACT_NET1 
HDD_PRSNT_NET0 
HDD_PRSNT_NET1 
DRV_ACT_1 
SW_PWR_HDD0 
SW_HDD0_P 
SW_PWR_R_HDD0 
SW_HDD1_P 
SW_PWR_R_HDD1 
SW_HDD1_N 
SW_PWR_HDD1 
DRIVE_PWR0 
DRIVE_PWR1 
DRIVE_ACT_0 
DRIVE_ACT_1 
FLT_HDD0 
FLT_HDD1 
FLT_HDD0_DRIVE 
FLT_HDD1_DRIVE 
FLT_HDD1_B 
ACT_HDD0 
ACT_HDD1 
FLT_HDD0_B 
SW_HDD0_G SW_HDD0_N 
SW_HDD1_G 
HDD1_LED_G 
HDD0_LED_G 
DRV_ACT_0 
HDD0_LED_B 
HDD1_LED_B 
P5V_HDD0 
P12V_HDD0 
P5V_HDD1 
P12V_HDD1 
P3V3 
P3V3 
P12V 
P5VA 
P12V_DRIVE_0 
P12V 
P5V_DRIVE_0 
P3V3 
P12V 
P5VA 
P12V_DRIVE_1 
P12V 
P5V_DRIVE_1 
P3V3 
P3V3 
P3V3 
P3V3 
P3V3 
P5VA 
P5VA 
P5V_HDD0 
P12V_HDD0 
P5V_HDD1 
P12V_HDD1 
P3V3 
P3V3 
P3V3 
P3V3 
P12V 
P12V 
P12V 
P5VA_HDD0_LED 
P12V 
P5VA_HDD1_LED 
P5VA 
P3V3 
P3V3_HDD0_LED 
P3V3 
P5VA 
P3V3_HDD1_LED 
SAS2x28_A_HDD0_TX_+ 12 
SAS2x28_A_HDD0_TX_- 12 
SAS2x28_A_HDD0_RX_- 12 
SAS2x28_A_HDD0_RX_+ 12 
SAS2x28_B_HDD0_TX_+ 12 
SAS2x28_B_HDD0_TX_- 12 
SAS2x28_B_HDD0_RX_- 12 
SAS2x28_B_HDD0_RX_+ 12 
HDD_PRSNT0 13 
SAS2x28_A_HDD0_FLT 12 
SAS2x28_B_HDD0_FLT 12 
SAS2x28_A_HDD1_FLT 12 
SAS2x28_B_HDD1_FLT 12 
SAS2x28_A_HDD1_TX_+ 12 
SAS2x28_A_HDD1_TX_- 12 
SAS2x28_A_HDD1_RX_- 12 
SAS2x28_A_HDD1_RX_+ 12 
SAS2x28_B_HDD1_TX_+ 12 
SAS2x28_B_HDD1_TX_- 12 
SAS2x28_B_HDD1_RX_- 12 
SAS2x28_B_HDD1_RX_+ 12 
HDD_PRSNT1 13 
SAS_EXP_A_PWR1 13 
SAS_EXP_B_PWR1 13 
SAS_EXP_A_PWR0 13 
SAS_EXP_B_PWR0 13 
Title 
Size Document Number Rev 
Date: Sheet 
of 
KNOX_DPB -1 
HDD CNs 0-1 
C
3 21 Thursday, October 11, 2012 
Wiwynn 
H/W R&D Dept. II 
8F,90,Sec. 1,Hsin Tai Wu Rd, 
Hsichih, Taipei Hsien 221, Taiwan, R.O.C 
Title 
Size Document Number Rev 
Date: Sheet 
of 
KNOX_DPB -1 
HDD CNs 0-1 
C
3 21 Thursday, October 11, 2012 
Wiwynn 
H/W R&D Dept. II 
8F,90,Sec. 1,Hsin Tai Wu Rd, 
Hsichih, Taipei Hsien 221, Taiwan, R.O.C 
Title 
Size Document Number Rev 
Date: Sheet 
of 
KNOX_DPB -1 
HDD CNs 0-1 
C
3 21 Thursday, October 11, 2012 
Wiwynn 
H/W R&D Dept. II 
8F,90,Sec. 1,Hsin Tai Wu Rd, 
Hsichih, Taipei Hsien 221, Taiwan, R.O.C 
C100 SCD01U50V2KX-1GP C100 SCD01U50V2KX-1GP 1 2
R489 
1KR2F-3-GP 
R489 
1KR2F-3-GP 
1 2
R122 
4K7R2J-2-GP 
R122 
4K7R2J-2-GP 
1 2
S
S
S
G D
D
D
D
U5 
P2003EVG-GP 
S
S
S
G D
D
D
D
U5 
P2003EVG-GP 
1
2
3
4 5
6
7
8
U1 
74LVC1G08GW-1-GP 
U1 
74LVC1G08GW-1-GP 
B 1
A 2
GND 3Y4
VCC 5
SKT2 
SKT-SATA14P-15P-12-GP 
SKT2 
SKT-SATA14P-15P-12-GP 
S1 
S2 
S3 
S4 
S5 
S6 
S7 
S8 
S9 
S10 
S11 
S12 
S13 
S14 
P1 
P2 
P3 
P4 
P5 
P6 
P7 
P8 
P9 
P10 
P11 
P12 
P13 
P14 
NP2 
NP1 
P15 
H2 
H1 
R513 
0R1206-PAD-1-GP 
R513 
0R1206-PAD-1-GP 
1 2
R125 
220R3F-1-GP 
R125 
220R3F-1-GP 
1 2
Q35 
PMBS3904-1-GP 
Q35 
PMBS3904-1-GP 
3
1
2
TP25TPAD32-GP TP25TPAD32-GP 1 U3 
74LVC1G08GW-1-GP 
U3 
74LVC1G08GW-1-GP 
B1
A2
GND 3 Y 4
VCC 5
C122 
SC1U16V3KX-5GP 
C122 
SC1U16V3KX-5GP 
1 2
R114 
10KR2F-2-GP 
R114 
10KR2F-2-GP 
1 2
R111 
220R3F-1-GP 
R111 
220R3F-1-GP 
1 2
C103 SCD01U50V2KX-1GP C103 SCD01U50V2KX-1GP 1 2
R424 
4K7R2J-2-GP 
R424 
4K7R2J-2-GP 
1 2
C130 
SC1U25V3KX-1-GP 
C130 
SC1U25V3KX-1-GP 
1 2
C102 
SCD1U10V2KX-5GP 
C102 
SCD1U10V2KX-5GP 
1 2
R100 
2R2010J-1-GP 
R100 
2R2010J-1-GP 
1 2
C120 SCD01U50V2KX-1GP C120 SCD01U50V2KX-1GP 1 2
U6 
74LVC1G08GW-1-GP 
U6 
74LVC1G08GW-1-GP 
B1
A2
GND 3 Y 4
VCC 5
R425 
4K7R2J-2-GP 
R425 
4K7R2J-2-GP 
1 2
R121 
2R2010J-1-GP 
R121 
2R2010J-1-GP 
1 2
F3 
POLYSW-2A6V-4-GP 
DY F3 
POLYSW-2A6V-4-GP 
DY 1 2
R124 
2R2010J-1-GP 
R124 
2R2010J-1-GP 
1 2
C113 
SC10U25V6KX-1GP 
C113 
SC10U25V6KX-1GP 
1 2
R428 
4K7R2J-2-GP 
R428 
4K7R2J-2-GP 
1 2
R123 
4K7R2J-2-GP 
R123 
4K7R2J-2-GP 
1 2
C108 
SCD01U50V2KX-1GP 
C108 
SCD01U50V2KX-1GP 
1 2
C125 
SCD1U10V2KX-5GP 
C125 
SCD1U10V2KX-5GP 
1 2
C115 
SC1U25V3KX-1-GP 
C115 
SC1U25V3KX-1-GP 
1 2
R515 
0R0805-PAD-2-GP 
R515 
0R0805-PAD-2-GP 
1 2
R422 
4K7R2J-2-GP 
R422 
4K7R2J-2-GP 
1 2
R117 
330R2F-GP 
R117 
330R2F-GP 
1 2
R112 
0R2J-2-GP 
R112 
0R2J-2-GP 
1 2
R408 
0R2J-2-GP 
R408 
0R2J-2-GP 
1 2
R409 
0R2J-2-GP 
R409 
0R2J-2-GP 
1 2
R126 
0R2J-2-GP 
R126 
0R2J-2-GP 
1 2
C118 SCD01U50V2KX-1GP C118 SCD01U50V2KX-1GP 1 2
Q1 
2N7002DW-7F-GP 
Q1 
2N7002DW-7F-GP 
1
2
3 4
5
6
F4 
FUSE-3A15V-GP 
DY F4 
FUSE-3A15V-GP 
DY 12
R344 
10KR2F-2-GP 
R344 
10KR2F-2-GP 
1 2
R343 
0R2J-2-GP 
R343 
0R2J-2-GP 
1 2
R120 
4K7R2J-2-GP 
R120 
4K7R2J-2-GP 1 2
R116 
0R2J-2-GP 
R116 
0R2J-2-GP 
1 2
C121 SCD01U50V2KX-1GP C121 SCD01U50V2KX-1GP 1 2
S
S
S
G D
D
D
D
Q2 
AO4406AL-GP 
S
S
S
G D
D
D
D
Q2 
AO4406AL-GP 
1
2
3
4 5
6
7
8
TP26TPAD32-GP TP26TPAD32-GP 1
R127 
0R2J-2-GP 
R127 
0R2J-2-GP 
1 2
R108 
4K7R2J-2-GP 
R108 
4K7R2J-2-GP 
1 2
R102 
402R2F-GP 
R102 
402R2F-GP 
1 2
Q31 
2N7002DW-7F-GP 
Q31 
2N7002DW-7F-GP 
1
2
34
5
6
C104 SCD01U50V2KX-1GP C104 SCD01U50V2KX-1GP 1 2
Q4 
2N7002DW-7F-GP 
Q4 
2N7002DW-7F-GP 1
2
3 4
5
6
C128 
SC10U25V6KX-1GP 
C128 
SC10U25V6KX-1GP 
1 2
R342 
10KR2F-2-GP 
R342 
10KR2F-2-GP 
1 2
LED1 
LED-RB-4-GP 
LED1 
LED-RB-4-GP 
1
3 2
4
R353 
0R2J-2-GP 
R353 
0R2J-2-GP 
1 2
R512 
0R1206-PAD-1-GP 
R512 
0R1206-PAD-1-GP 
1 2
C126 
SC10U25V6KX-1GP 
C126 
SC10U25V6KX-1GP 
1 2
R488 
1KR2F-3-GP 
R488 
1KR2F-3-GP 
1 2
R103 
0R2J-2-GP 
R103 
0R2J-2-GP 
1 2
Q49 
2N7002-11-GP 
Q49 
2N7002-11-GP 
G
SD
R115 
402R2F-GP 
R115 
402R2F-GP 
1 2
C105 SCD01U50V2KX-1GP C105 SCD01U50V2KX-1GP 1 2
R104 
330R2F-GP 
R104 
330R2F-GP 
1 2
C110 
SCD1U10V2KX-5GP 
C110 
SCD1U10V2KX-5GP 
1 2
R118 
0R2J-2-GP 
R118 
0R2J-2-GP 
1 2
R429 
4K7R2J-2-GP 
R429 
4K7R2J-2-GP 
1 2
U4 
74LVC1G08GW-1-GP 
U4 
74LVC1G08GW-1-GP 
B 1
A 2
GND 3Y4
VCC 5
C114 
SC10U25V6KX-1GP 
C114 
SC10U25V6KX-1GP 
1 2
R423 
4K7R2J-2-GP 
R423 
4K7R2J-2-GP 
1 2
R107 
1KR2F-3-GP 
DY 
R107 
1KR2F-3-GP 
DY 
1 2
Q34 
PMBS3904-1-GP 
Q34 
PMBS3904-1-GP 
3
1
2
F2 
FUSE-3A15V-GP 
DY F2 
FUSE-3A15V-GP 
DY 12
C107 
SC10U16V6KX-2GP 
C107 
SC10U16V6KX-2GP 
1 2
C111 
SC10U25V6KX-1GP 
C111 
SC10U25V6KX-1GP 
1 2
R426 
4K7R2J-2-GP 
R426 
4K7R2J-2-GP 
1 2
C131 
SCD01U50V2KX-1GP 
C131 
SCD01U50V2KX-1GP 
1 2
R514 
0R0805-PAD-2-GP 
R514 
0R0805-PAD-2-GP 
1 2
S
S
S
G D
D
D
D
U2 
P2003EVG-GP 
S
S
S
G D
D
D
D
U2 
P2003EVG-GP 
1
2
3
4 5
6
7
8
R101 
10KR2F-2-GP 
R101 
10KR2F-2-GP 
1 2
F1 
POLYSW-2A6V-4-GP 
DY F1 
POLYSW-2A6V-4-GP 
DY 1 2
C112 
SC10U25V6KX-1GP 
C112 
SC10U25V6KX-1GP 
1 2
R110 
2R2010J-1-GP 
R110 
2R2010J-1-GP 
1 2
R427 
4K7R2J-2-GP 
R427 
4K7R2J-2-GP 
1 2
C119 SCD01U50V2KX-1GP C119 SCD01U50V2KX-1GP 1 2
C123 
SC10U16V6KX-2GP 
C123 
SC10U16V6KX-2GP 
1 2
Q50 
2N7002-11-GP 
Q50 
2N7002-11-GP 
G
SD
LED2 
LED-RB-4-GP 
LED2 
LED-RB-4-GP 
1
3 2
4
S
S
S
G D
D
D
D
Q3 
AO4406AL-GP 
S
S
S
G D
D
D
D
Q3 
AO4406AL-GP 
1
2
3
4 5
6
7
8
R109 
4K7R2J-2-GP 
R109 
4K7R2J-2-GP 
1 2
R119 
1KR2F-3-GP 
DY 
R119 
1KR2F-3-GP 
DY 
1 2
SKT1 
SKT-SATA14P-15P-12-GP 
SKT1 
SKT-SATA14P-15P-12-GP 
S1 
S2 
S3 
S4 
S5 
S6 
S7 
S8 
S9 
S10 
S11 
S12 
S13 
S14 
P1 
P2 
P3 
P4 
P5 
P6 
P7 
P8 
P9 
P10 
P11 
P12 
P13 
P14 
NP2 
NP1 
P15 
H2 
H1 
Q32 
2N7002DW-7F-GP 
Q32 
2N7002DW-7F-GP 
1
2
34
5
6
R113 
0R2J-2-GP 
R113 
0R2J-2-GP 
1 2
C129 
SC10U25V6KX-1GP 
C129 
SC10U25V6KX-1GP 
1 2
C117 
SCD1U10V2KX-5GP 
C117 
SCD1U10V2KX-5GP 
1 2
R106 
4K7R2J-2-GP 
R106 
4K7R2J-2-GP 
1 2
C106 
SC1U16V3KX-5GP 
C106 
SC1U16V3KX-5GP 
1 2
C127 
SC10U25V6KX-1GP 
C127 
SC10U25V6KX-1GP 
1 2
R105 
0R2J-2-GP 
R105 
0R2J-2-GP 
1 2



5
5
4
4
3
3
2
2
1
1
D D
C C
B B
A A
N-Channel 
P-Channel 
N-Channel 
P-Channel 
HDD2 
HDD3 
ID=12A 
RDS(on) 
=11.5m ohm 
ID=12A 
RDS(on) 
=11.5m ohm 
ID=-9A 
RDS(on) 
=20m ohm 
ID=-9A 
RDS(on) 
=20m ohm 
1
1
0
0
1
1
HDD3_PWR EXP_A_PWR3 
OFF 
OFF 
OFF 
EXP_B_PWR3 
ON 
0
0
1
1
0
0
1
1
HDD2_PWR EXP_A_PWR2 
OFF 
OFF 
OFF 
EXP_B_PWR2 
ON 
0
0
1
1
0
0
1
1
HDD2_FLT_LED EXP_A_HDD2_FLT 
ON 
ON 
ON 
EXP_B_HDD2_FLT 
OFF 
0
0
1
1
0
0
1
1
HDD3_FLT_LED EXP_A_HDD3_FLT 
ON 
ON 
ON 
EXP_B_HDD3_FLT 
OFF 
0
0
Ihold=3A 
Itrip=6A 
Ihold=3A 
Itrip=6A 
Ihold=2A 
Itrip=4A 
Ihold=2A 
Itrip=4A 
EVT-3R 
20120620 
EVT-3R 
20120620 
DVT 
20120630 
DVT 
20120630 
BLUE VF=2.9V 
I=4.7mA 
BLUE VF=2.9V 
I=4.7mA 
AND GATE 
AND GATE 
AND GATE 
AND GATE 
DVT 
20120710 
RED VF=1.8V 
I=4.5mA 
RED VF=1.8V 
I=4.5mA 
DVT 
20120703 
DVT 
20120703 
DVT 
20120703 
DVT 
20120703 
DVT 
20120710 
DVT 
20120710 
DVT 
20120710 
DVT 
20120710 
DVT 
20120710 
DVT 
20120710 
DVT 
20120710 
DVT 
20120712 
DVT 
20120712 
DVT 
20120712 
DVT 
20120712 
DVT 
20120724 
DVT 
20120724 
PVT 
20121009 
PVT 
20121009 
PVT 
20121009 
PVT 
20121009 
FLT_NET_HDD3 
12V_PRE_3 
SAS2x28_Drive_RX_N_A3 
SAS2x28_Drive_RX_P_A3 
SAS2x28_Drive_RX_N_B3 
SAS2x28_Drive_RX_P_B3 
5V_PRE_3 
DRV_ACT_3 
12V_PRE_2 
SAS2x28_Drive_RX_N_A2 
SAS2x28_Drive_RX_P_A2 
SAS2x28_Drive_RX_N_B2 
SAS2x28_Drive_RX_P_B2 
5V_PRE_2 
HDD_PRSNT_NET2 
FLT_NET_HDD2 
DRV_ACT_NET2 DRV_ACT_2 
SW_PWR_R_HDD2 SW_PWR_HDD2 
SW_HDD3_P 
SW_PWR_R_HDD3 
SW_HDD3_N 
SW_PWR_HDD3 DRIVE_PWR3 
DRIVE_PWR2 
SW_HDD2_N 
DRV_ACT_NET3 
FLT_HDD2 
FLT_HDD3 
SW_HDD2_P 
FLT_HDD2_DRIVE 
FLT_HDD2_B 
DRIVE_ACT_2 
FLT_HDD3_B 
FLT_HDD3_DRIVE 
DRIVE_ACT_3 
ACT_HDD2 
ACT_HDD3 
SW_HDD2_G 
SW_HDD3_G 
HDD2_LED_G 
HDD3_LED_G 
HDD2_LED_B 
HDD3_LED_B 
HDD_PRSNT_NET3 
P5V_HDD3 
P12V_HDD3 
P3V3 
P5V_HDD2 
P12V_HDD2 
P3V3 P12V 
P5VA 
P12V_DRIVE_2 
P12V 
P5V_DRIVE_2 
P3V3 
P5V_HDD2 
P12V_HDD2 
P5V_HDD3 
P12V_HDD3 
P12V 
P5VA 
P12V_DRIVE_3 
P12V 
P5V_DRIVE_3 
P3V3 
P3V3 
P3V3 
P3V3 
P3V3 
P5VA 
P5VA 
P3V3 
P3V3 
P3V3 
P3V3 
P12V 
P12V 
P12V 
P12V 
P5VA_HDD2_LED P3V3 
P5VA 
P3V3_HDD2_LED 
P5VA_HDD3_LED P3V3 
P5VA 
P3V3_HDD3_LED 
SAS2x28_A_HDD3_FLT 12 
SAS2x28_B_HDD3_FLT 12 
SAS2x28_A_HDD3_TX_+ 12 
SAS2x28_A_HDD3_TX_- 12 
SAS2x28_A_HDD3_RX_- 12 
SAS2x28_A_HDD3_RX_+ 12 
SAS2x28_B_HDD3_TX_+ 12 
SAS2x28_B_HDD3_TX_- 12 
SAS2x28_B_HDD3_RX_- 12 
SAS2x28_B_HDD3_RX_+ 12 
HDD_PRSNT3 13 
SAS2x28_A_HDD2_TX_+ 12 
SAS2x28_A_HDD2_TX_- 12 
SAS2x28_A_HDD2_RX_- 12 
SAS2x28_A_HDD2_RX_+ 12 
SAS2x28_B_HDD2_TX_+ 12 
SAS2x28_B_HDD2_TX_- 12 
SAS2x28_B_HDD2_RX_- 12 
SAS2x28_B_HDD2_RX_+ 12 
HDD_PRSNT2 13 
SAS2x28_A_HDD2_FLT 12 
SAS2x28_B_HDD2_FLT 12 
SAS_EXP_A_PWR2 13 
SAS_EXP_B_PWR2 13 
SAS_EXP_A_PWR3 13 
SAS_EXP_B_PWR3 13 
Title 
Size Document Number Rev 
Date: Sheet 
of 
KNOX_SEB 
-1 
HDD CNs 2-3 
C
4 21 Thursday, October 11, 2012 
Wiwynn 
H/W R&D Dept. II 
8F,90,Sec. 1,Hsin Tai Wu Rd, 
Hsichih, Taipei Hsien 221, Taiwan, R.O.C 
Title 
Size Document Number Rev 
Date: Sheet 
of 
KNOX_SEB 
-1 
HDD CNs 2-3 
C
4 21 Thursday, October 11, 2012 
Wiwynn 
H/W R&D Dept. II 
8F,90,Sec. 1,Hsin Tai Wu Rd, 
Hsichih, Taipei Hsien 221, Taiwan, R.O.C 
Title 
Size Document Number Rev 
Date: Sheet 
of 
KNOX_SEB 
-1 
HDD CNs 2-3 
C
4 21 Thursday, October 11, 2012 
Wiwynn 
H/W R&D Dept. II 
8F,90,Sec. 1,Hsin Tai Wu Rd, 
Hsichih, Taipei Hsien 221, Taiwan, R.O.C 
R139 
220R3F-1-GP 
R139 
220R3F-1-GP 
1 2
R155 
0R2J-2-GP 
R155 
0R2J-2-GP 
1 2
SKT3 
SKT-SATA14P-15P-12-GP 
SKT3 
SKT-SATA14P-15P-12-GP 
S1 
S2 
S3 
S4 
S5 
S6 
S7 
S8 
S9 
S10 
S11 
S12 
S13 
S14 
P1 
P2 
P3 
P4 
P5 
P6 
P7 
P8 
P9 
P10 
P11 
P12 
P13 
P14 
NP2 
NP1 
P15 
H2 
H1 
C152 SCD01U50V2KX-1GP C152 SCD01U50V2KX-1GP 1 2
R435 
4K7R2J-2-GP 
R435 
4K7R2J-2-GP 
1 2
R490 
1KR2F-3-GP 
R490 
1KR2F-3-GP 
1 2
R154 
2R2010J-1-GP 
R154 
2R2010J-1-GP 
1 2
R142 
10KR2F-2-GP 
R142 
10KR2F-2-GP 
1 2
S
S
S
G D
D
D
D
Q7 
AO4406AL-GP 
S
S
S
G D
D
D
D
Q7 
AO4406AL-GP 
1
2
3
4 5
6
7
8
S
S
S
G D
D
D
D
U8 
P2003EVG-GP 
S
S
S
G D
D
D
D
U8 
P2003EVG-GP 
1
2
3
4 5
6
7
8
C146 
SC1U25V3KX-1-GP 
C146 
SC1U25V3KX-1-GP 
1 2
R129 
402R2F-GP 
R129 
402R2F-GP 
1 2
R140 
0R2J-2-GP 
R140 
0R2J-2-GP 
1 2
S
S
S
G D
D
D
D
Q5 
AO4406AL-GP 
S
S
S
G D
D
D
D
Q5 
AO4406AL-GP 
1
2
3
4 5
6
7
8
S
S
S
G D
D
D
D
U11 
P2003EVG-GP 
S
S
S
G D
D
D
D
U11 
P2003EVG-GP 
1
2
3
4 5
6
7
8
R134 
2R2010J-1-GP 
R134 
2R2010J-1-GP 
1 2
C161 
SC10U25V6KX-1GP 
C161 
SC10U25V6KX-1GP 
1 2
C150 SCD01U50V2KX-1GP C150 SCD01U50V2KX-1GP 1 2
Q33 
2N7002DW-7F-GP 
Q33 
2N7002DW-7F-GP 
1
2
34
5
6
R144 
0R2J-2-GP 
R144 
0R2J-2-GP 
1 2
C153 SCD01U50V2KX-1GP C153 SCD01U50V2KX-1GP 1 2
R519 
0R1206-PAD-1-GP 
R519 
0R1206-PAD-1-GP 
1 2
Q37 
PMBS3904-1-GP 
Q37 
PMBS3904-1-GP 3
1
2
R136 
4K7R2J-2-GP 
R136 
4K7R2J-2-GP 
1 2
C159 
SC10U25V6KX-1GP 
C159 
SC10U25V6KX-1GP 
1 2
TP28TPAD32-GP TP28TPAD32-GP 1
C155 
SC10U16V6KX-2GP 
C155 
SC10U16V6KX-2GP 
1 2
C144 
SC10U25V6KX-1GP 
C144 
SC10U25V6KX-1GP 
1 2
SKT4 
SKT-SATA14P-15P-12-GP 
SKT4 
SKT-SATA14P-15P-12-GP 
S1 
S2 
S3 
S4 
S5 
S6 
S7 
S8 
S9 
S10 
S11 
S12 
S13 
S14 
P1 
P2 
P3 
P4 
P5 
P6 
P7 
P8 
P9 
P10 
P11 
P12 
P13 
P14 
NP2 
NP1 
P15 
H2 
H1 
Q53 
2N7002-11-GP 
Q53 
2N7002-11-GP 
G
SD
C139 
SC10U16V6KX-2GP 
C139 
SC10U16V6KX-2GP 
1 2
U10 
74LVC1G08GW-1-GP 
U10 
74LVC1G08GW-1-GP 
B 1
A 2
GND 3Y4
VCC 5
R432 
4K7R2J-2-GP 
R432 
4K7R2J-2-GP 
1 2
C154 
SC1U16V3KX-5GP 
C154 
SC1U16V3KX-5GP 
1 2
C142 
SC10U25V6KX-1GP 
C142 
SC10U25V6KX-1GP 
1 2
F7 
POLYSW-2A6V-4-GP 
DY F7 
POLYSW-2A6V-4-GP 
DY 1 2
U12 
74LVC1G08GW-1-GP 
U12 
74LVC1G08GW-1-GP 
B1
A2
GND 3 Y 4
VCC 5
U7 
74LVC1G08GW-1-GP 
U7 
74LVC1G08GW-1-GP 
B 1
A 2
GND 3Y4
VCC 5
R128 
10KR2F-2-GP 
R128 
10KR2F-2-GP 
1 2
R153 
0R2J-2-GP 
R153 
0R2J-2-GP 
1 2
R431 
4K7R2J-2-GP 
R431 
4K7R2J-2-GP 
1 2
R436 
4K7R2J-2-GP 
R436 
4K7R2J-2-GP 
1 2
R149 
4K7R2J-2-GP 
R149 
4K7R2J-2-GP 
1 2
C137 SCD01U50V2KX-1GP C137 SCD01U50V2KX-1GP 1 2
R151 
2R2010J-1-GP 
R151 
2R2010J-1-GP 
1 2
R135 
1KR2F-3-GP 
DY R135 
1KR2F-3-GP 
DY 
1 2
R148 
4K7R2J-2-GP 
R148 
4K7R2J-2-GP 
1 2
F8 
FUSE-3A15V-GP 
DY F8 
FUSE-3A15V-GP 
DY 12
R410 
0R2J-2-GP 
R410 
0R2J-2-GP 
1 2
R133 
4K7R2J-2-GP 
R133 
4K7R2J-2-GP 
1 2
R369 
0R2J-2-GP 
R369 
0R2J-2-GP 
1 2
R138 
2R2010J-1-GP 
R138 
2R2010J-1-GP 
1 2
R365 
0R2J-2-GP 
R365 
0R2J-2-GP 
1 2
C135 SCD01U50V2KX-1GP C135 SCD01U50V2KX-1GP 1 2
R146 
0R2J-2-GP 
R146 
0R2J-2-GP 
1 2
C133 
SCD1U10V2KX-5GP 
C133 
SCD1U10V2KX-5GP 
1 2
R434 
4K7R2J-2-GP 
R434 
4K7R2J-2-GP 
1 2
R491 
1KR2F-3-GP 
R491 
1KR2F-3-GP 
1 2
R363 
10KR2F-2-GP 
R363 
10KR2F-2-GP 
1 2
R516 
0R0805-PAD-2-GP 
R516 
0R0805-PAD-2-GP 
1 2
C134 SCD01U50V2KX-1GP C134 SCD01U50V2KX-1GP 1 2
C156 
SCD01U50V2KX-1GP 
C156 
SCD01U50V2KX-1GP 
1 2
R518 
0R0805-PAD-2-GP 
R518 
0R0805-PAD-2-GP 
1 2
C162 
SC10U25V6KX-1GP 
C162 
SC10U25V6KX-1GP 
1 2
R411 
0R2J-2-GP 
R411 
0R2J-2-GP 
1 2
C151 SCD01U50V2KX-1GP C151 SCD01U50V2KX-1GP 1 2
LED3 
LED-RB-4-GP 
LED3 
LED-RB-4-GP 
1
3 2
4
LED4 
LED-RB-4-GP 
LED4 
LED-RB-4-GP 
1
3 2
4
C160 
SC10U25V6KX-1GP 
C160 
SC10U25V6KX-1GP 
1 2
Q36 
PMBS3904-1-GP 
Q36 
PMBS3904-1-GP 
3
1
2
Q51 
2N7002-11-GP 
Q51 
2N7002-11-GP 
G
SD
C145 
SC10U25V6KX-1GP 
C145 
SC10U25V6KX-1GP 
1 2
R130 
0R2J-2-GP 
R130 
0R2J-2-GP 
1 2
F5 
POLYSW-2A6V-4-GP 
DY F5 
POLYSW-2A6V-4-GP 
DY 1 2
C158 
SCD1U10V2KX-5GP 
C158 
SCD1U10V2KX-5GP 
1 2
C147 
SCD01U50V2KX-1GP 
C147 
SCD01U50V2KX-1GP 
1 2
Q6 
2N7002DW-7F-GP 
Q6 
2N7002DW-7F-GP 
1
2
3 4
5
6
C143 
SC10U25V6KX-1GP 
C143 
SC10U25V6KX-1GP 
1 2
R132 
0R2J-2-GP 
R132 
0R2J-2-GP 
1 2
R366 
10KR2F-2-GP 
R366 
10KR2F-2-GP 
1 2
C138 
SC1U16V3KX-5GP 
C138 
SC1U16V3KX-5GP 
1 2
R131 
330R2F-GP 
R131 
330R2F-GP 
1 2
R433 
4K7R2J-2-GP 
R433 
4K7R2J-2-GP 
1 2
TP27TPAD32-GP TP27TPAD32-GP 1
C163 
SC1U25V3KX-1-GP 
C163 
SC1U25V3KX-1-GP 
1 2
Q52 
2N7002DW-7F-GP 
Q52 
2N7002DW-7F-GP 
1
2
34
5
6
F6 
FUSE-3A15V-GP 
DY F6 
FUSE-3A15V-GP 
DY 12
R150 
4K7R2J-2-GP 
R150 
4K7R2J-2-GP 
1 2
R517 
0R1206-PAD-1-GP 
R517 
0R1206-PAD-1-GP 
1 2
R145 
330R2F-GP 
R145 
330R2F-GP 
1 2
Q8 
2N7002DW-7F-GP 
Q8 
2N7002DW-7F-GP 
1
2
3 4
5
6R430 
4K7R2J-2-GP 
R430 
4K7R2J-2-GP 
1 2
R437 
4K7R2J-2-GP 
R437 
4K7R2J-2-GP 
1 2
R141 
0R2J-2-GP 
R141 
0R2J-2-GP 
1 2
C136 SCD01U50V2KX-1GP C136 SCD01U50V2KX-1GP 1 2
C149 
SCD1U10V2KX-5GP 
C149 
SCD1U10V2KX-5GP 
1 2
R152 
220R3F-1-GP 
R152 
220R3F-1-GP 
1 2
R143 
402R2F-GP 
R143 
402R2F-GP 
1 2
R147 
1KR2F-3-GP 
DY R147 
1KR2F-3-GP 
DY 
1 2
C141 
SCD1U10V2KX-5GP 
C141 
SCD1U10V2KX-5GP 
1 2
R137 
4K7R2J-2-GP 
R137 
4K7R2J-2-GP 
1 2
U9 
74LVC1G08GW-1-GP 
U9 
74LVC1G08GW-1-GP 
B1
A2
GND 3 Y 4
VCC 5



5
5
4
4
3
3
2
2
1
1
D D
C C
B B
A A
N-Channel 
P-Channel 
N-Channel 
P-Channel 
HDD4 
HDD5 
ID=12A 
RDS(on) 
=11.5m ohm 
ID=12A 
RDS(on) 
=11.5m ohm 
ID=-9A 
RDS(on) 
=20m ohm 
ID=-9A 
RDS(on) 
=20m ohm 
1
1
0
0
1
1
HDD4_PWR EXP_A_PWR4 
OFF 
OFF 
OFF 
EXP_B_PWR4 
ON 
0
0
1
1
0
0
1
1
HDD5_PWR EXP_A_PWR5 
OFF 
OFF 
OFF 
EXP_B_PWR5 
ON 
0
0
1
1
0
0
1
1
HDD4_FLT_LED EXP_A_HDD4_FLT 
ON 
ON 
ON 
EXP_B_HDD4_FLT 
OFF 
0
0
1
1
0
0
1
1
HDD5_FLT_LED EXP_A_HDD5_FLT 
ON 
ON 
ON 
EXP_B_HDD5_FLT 
OFF 
0
0
Ihold=3A 
Itrip=6A 
Ihold=3A 
Itrip=6A 
Ihold=2A 
Itrip=4A 
Ihold=2A 
Itrip=4A 
EVT-3R 
20120620 
EVT-3R 
20120620 
DVT 
20120630 
DVT 
20120630 
BLUE VF=2.9V 
I=4.7mA 
BLUE VF=2.9V 
I=4.7mA 
AND GATE 
AND GATE 
AND GATE 
AND GATE 
DVT 
20120710 
DVT 
20120710 
RED VF=1.8V 
I=4.5mA 
RED VF=1.8V 
I=4.5mA 
DVT 
20120703 
DVT 
20120703 
DVT 
20120703 
DVT 
20120703 
DVT 
20120710 
DVT 
20120710 
DVT 
20120710 
DVT 
20120710 
DVT 
20120710 
DVT 
DVT 
20120710 
DVT 
20120712 
DVT 
20120712 
DVT 
20120712 
DVT 
20120712 
DVT 
20120724 
DVT 
20120724 
PVT 
20121009 
PVT 
20121009 
PVT 
20121009 
PVT 
20121009 
12V_PRE_5 
SAS2x28_Drive_RX_N_A5 
SAS2x28_Drive_RX_P_A5 
SAS2x28_Drive_RX_N_B5 
SAS2x28_Drive_RX_P_B5 
5V_PRE_5 
DRV_ACT_4 
FLT_NET_HDD4 
12V_PRE_4 
SAS2x28_Drive_RX_P_A4 
SAS2x28_Drive_RX_P_B4 
DRV_ACT_NET4 
HDD_PRSNT_NET4 
FLT_NET_HDD5 
DRV_ACT_NET5 DRV_ACT_5 
SW_PWR_HDD4 
SW_HDD4_P 
SW_PWR_R_HDD4 
SW_HDD4_N 
SW_PWR_HDD5 
SW_HDD5_P 
SW_PWR_R_HDD5 
SW_HDD5_N 
DRIVE_PWR4 
DRIVE_PWR5 
SAS2x28_Drive_RX_N_A4 
SAS2x28_Drive_RX_N_B4 
FLT_HDD4 
FLT_HDD5 
FLT_HDD4_DRIVE 
5V_PRE_4 
FLT_HDD5_B 
FLT_HDD5_DRIVE 
DRIVE_ACT_5 
FLT_HDD4_B 
DRIVE_ACT_4 
ACT_HDD4 
ACT_HDD5 
SW_HDD4_G 
SW_HDD5_G 
HDD4_LED_G 
HDD5_LED_G 
HDD4_LED_B 
HDD5_LED_B 
HDD_PRSNT_NET5 
P3V3 
P5V_HDD5 
P12V_HDD5 
P5V_HDD4 
P3V3 P12V_HDD4 
P5V_HDD4 
P12V_HDD4 
P12V 
P5VA 
P12V_DRIVE_4 
P12V 
P5V_DRIVE_4 
P3V3 
P12V 
P5VB 
P12V_DRIVE_5 
P12V 
P5V_DRIVE_5 
P3V3 
P5V_HDD5 
P12V_HDD5 
P3V3 
P3V3 
P3V3 
P3V3 
P5VA 
P5VB 
P3V3 
P3V3 
P3V3 
P3V3 
P12V 
P12V 
P12V 
P12V 
P5VA_HDD4_LED P3V3 
P5VA 
P3V3_HDD4_LED 
P5VB_HDD5_LED P3V3 
P5VB 
P3V3_HDD5_LED 
SAS2x28_A_HDD5_TX_+ 12 
SAS2x28_A_HDD5_TX_- 12 
SAS2x28_A_HDD5_RX_- 12 
SAS2x28_A_HDD5_RX_+ 12 
SAS2x28_B_HDD5_TX_+ 12 
SAS2x28_B_HDD5_TX_- 12 
SAS2x28_B_HDD5_RX_- 12 
SAS2x28_B_HDD5_RX_+ 12 
HDD_PRSNT5 13 
SAS2x28_A_HDD4_TX_+ 12 
SAS2x28_A_HDD4_TX_- 12 
SAS2x28_A_HDD4_RX_- 12 
SAS2x28_A_HDD4_RX_+ 12 
SAS2x28_B_HDD4_TX_+ 12 
SAS2x28_B_HDD4_TX_- 12 
SAS2x28_B_HDD4_RX_- 12 
SAS2x28_B_HDD4_RX_+ 12 
HDD_PRSNT4 13 
SAS2x28_A_HDD5_FLT 12 
SAS2x28_B_HDD5_FLT 12 
SAS_EXP_A_PWR4 13 
SAS_EXP_B_PWR4 13 
SAS2x28_A_HDD4_FLT 12 
SAS2x28_B_HDD4_FLT 12 
SAS_EXP_A_PWR5 13 
SAS_EXP_B_PWR5 13 
Title 
Size Document Number Rev 
Date: Sheet 
of 
KNOX_DPB -1 
HDD CNs 4-5 
C
5 21 Thursday, October 11, 2012 
Wiwynn 
H/W R&D Dept. II 
8F,90,Sec. 1,Hsin Tai Wu Rd, 
Hsichih, Taipei Hsien 221, Taiwan, R.O.C 
Title 
Size Document Number Rev 
Date: Sheet 
of 
KNOX_DPB -1 
HDD CNs 4-5 
C
5 21 Thursday, October 11, 2012 
Wiwynn 
H/W R&D Dept. II 
8F,90,Sec. 1,Hsin Tai Wu Rd, 
Hsichih, Taipei Hsien 221, Taiwan, R.O.C 
Title 
Size Document Number Rev 
Date: Sheet 
of 
KNOX_DPB -1 
HDD CNs 4-5 
C
5 21 Thursday, October 11, 2012 
Wiwynn 
H/W R&D Dept. II 
8F,90,Sec. 1,Hsin Tai Wu Rd, 
Hsichih, Taipei Hsien 221, Taiwan, R.O.C 
Q56 
2N7002DW-7F-GP 
Q56 
2N7002DW-7F-GP 
1
2
34
5
6
R158 
0R2J-2-GP 
R158 
0R2J-2-GP 
1 2
Q39 
PMBS3904-1-GP 
Q39 
PMBS3904-1-GP 3
1
2
R521 
0R1206-PAD-1-GP 
R521 
0R1206-PAD-1-GP 
1 2
C194 
SC10U25V6KX-1GP 
C194 
SC10U25V6KX-1GP 
1 2
C192 
SC10U25V6KX-1GP 
C192 
SC10U25V6KX-1GP 
1 2
R171 
402R2F-GP 
R171 
402R2F-GP 
1 2
LED5 
LED-RB-4-GP 
LED5 
LED-RB-4-GP 
1
3 2
4
R445 
4K7R2J-2-GP 
R445 
4K7R2J-2-GP 
1 2
C176 
SC10U25V6KX-1GP 
C176 
SC10U25V6KX-1GP 
1 2
Q54 
2N7002DW-7F-GP 
Q54 
2N7002DW-7F-GP 
1
2
34
5
6
R165 
4K7R2J-2-GP 
R165 
4K7R2J-2-GP 
1 2
R181 
4K7R2J-2-GP 
R181 
4K7R2J-2-GP 
1 2
Q57 
2N7002-11-GP 
Q57 
2N7002-11-GP 
G
SD
C172 
SC1U16V3KX-5GP 
C172 
SC1U16V3KX-5GP 
1 2
Q55 
2N7002-11-GP 
Q55 
2N7002-11-GP 
G
SD
R440 
4K7R2J-2-GP 
R440 
4K7R2J-2-GP 
1 2
C168 SCD01U50V2KX-1GP C168 SCD01U50V2KX-1GP 1 2
C174 
SC10U25V6KX-1GP 
C174 
SC10U25V6KX-1GP 
1 2
TP29TPAD32-GP TP29TPAD32-GP 1
R174 
0R2J-2-GP 
R174 
0R2J-2-GP 
1 2
R164 
1KR2F-3-GP 
DY R164 
1KR2F-3-GP 
DY 
1 2
R167 
220R3F-1-GP 
R167 
220R3F-1-GP 
1 2
C173 
SC10U16V6KX-2GP 
C173 
SC10U16V6KX-2GP 
1 2
R172 
0R2J-2-GP 
R172 
0R2J-2-GP 
1 2
R523 
0R1206-PAD-1-GP 
R523 
0R1206-PAD-1-GP 
1 2
U18 
74LVC1G08GW-1-GP 
U18 
74LVC1G08GW-1-GP 
B1
A2
GND 3 Y 4
VCC 5
C188 
SC1U16V3KX-5GP 
C188 
SC1U16V3KX-5GP 
1 2
F9 
POLYSW-2A6V-4-GP 
DY F9 
POLYSW-2A6V-4-GP 
DY 1 2
R173 
330R2F-GP 
R173 
330R2F-GP 
1 2
C169 SCD01U50V2KX-1GP C169 SCD01U50V2KX-1GP 1 2
R441 
4K7R2J-2-GP 
R441 
4K7R2J-2-GP 
1 2
S
S
S
G D
D
D
D
Q11 
AO4406AL-GP 
S
S
S
G D
D
D
D
Q11 
AO4406AL-GP 
1
2
3
4 5
6
7
8
F10 
FUSE-3A15V-GP 
DY F10 
FUSE-3A15V-GP 
DY 12
R183 
0R2J-2-GP 
R183 
0R2J-2-GP 
1 2
R412 
0R2J-2-GP 
R412 
0R2J-2-GP 
1 2
Q38 
PMBS3904-1-GP 
Q38 
PMBS3904-1-GP 3
1
2
R492 
1KR2F-3-GP 
R492 
1KR2F-3-GP 
1 2
LED6 
LED-RB-4-GP 
LED6 
LED-RB-4-GP 
1
3 2
4
R413 
0R2J-2-GP 
R413 
0R2J-2-GP 
1 2
R177 
220R3F-1-GP 
R177 
220R3F-1-GP 
1 2
R168 
0R2J-2-GP 
R168 
0R2J-2-GP 
1 2
S
S
S
G D
D
D
D
U17 
P2003EVG-GP 
S
S
S
G D
D
D
D
U17 
P2003EVG-GP 
1
2
3
4 5
6
7
8
U16 
74LVC1G08GW-1-GP 
U16 
74LVC1G08GW-1-GP 
B 1
A 2
GND 3Y4
VCC 5
C189 
SC10U16V6KX-2GP 
C189 
SC10U16V6KX-2GP 
1 2
R176 
4K7R2J-2-GP 
R176 
4K7R2J-2-GP 
1 2
R374 
0R2J-2-GP 
R374 
0R2J-2-GP 
1 2
C178 
SCD01U50V2KX-1GP 
C178 
SCD01U50V2KX-1GP 
1 2
C193 
SC10U25V6KX-1GP 
C193 
SC10U25V6KX-1GP 
1 2
R159 
330R2F-GP 
R159 
330R2F-GP 
1 2
C190 
SCD01U50V2KX-1GP 
C190 
SCD01U50V2KX-1GP 
1 2
C195 
SC1U25V3KX-1-GP 
C195 
SC1U25V3KX-1-GP 
1 2
SKT6 
SKT-SATA14P-15P-12-GP 
SKT6 
SKT-SATA14P-15P-12-GP 
S1 
S2 
S3 
S4 
S5 
S6 
S7 
S8 
S9 
S10 
S11 
S12 
S13 
S14 
P1 
P2 
P3 
P4 
P5 
P6 
P7 
P8 
P9 
P10 
P11 
P12 
P13 
P14 
NP2 
NP1 
P15 
H2 
H1 
Q12 
2N7002DW-7F-GP 
Q12 
2N7002DW-7F-GP 
1
2
3 4
5
6
R376 
0R2J-2-GP 
R376 
0R2J-2-GP 
1 2
R444 
4K7R2J-2-GP 
R444 
4K7R2J-2-GP 
1 2
C191 
SC10U25V6KX-1GP 
C191 
SC10U25V6KX-1GP 
1 2
C177 
SC10U25V6KX-1GP 
C177 
SC10U25V6KX-1GP 
1 2
R166 
4K7R2J-2-GP 
R166 
4K7R2J-2-GP 
1 2
SKT5 
SKT-SATA14P-15P-12-GP 
SKT5 
SKT-SATA14P-15P-12-GP 
S1 
S2 
S3 
S4 
S5 
S6 
S7 
S8 
S9 
S10 
S11 
S12 
S13 
S14 
P1 
P2 
P3 
P4 
P5 
P6 
P7 
P8 
P9 
P10 
P11 
P12 
P13 
P14 
NP2 
NP1 
P15 
H2 
H1 
C179 
SC1U25V3KX-1-GP 
C179 
SC1U25V3KX-1-GP 
1 2
R370 
10KR2F-2-GP 
R370 
10KR2F-2-GP 
1 2
R182 
0R2J-2-GP 
R182 
0R2J-2-GP 
1 2
C175 
SC10U25V6KX-1GP 
C175 
SC10U25V6KX-1GP 
1 2
R180 
4K7R2J-2-GP 
R180 
4K7R2J-2-GP 
1 2
C183 SCD01U50V2KX-1GP C183 SCD01U50V2KX-1GP 1 2
R162 
4K7R2J-2-GP 
R162 
4K7R2J-2-GP 
1 2
TP30 
TPAD32-GP 
TP30 
TPAD32-GP 
1
U13 
74LVC1G08GW-1-GP 
U13 
74LVC1G08GW-1-GP 
B 1
A 2
GND 3Y4
VCC 5
R179 
1KR2F-3-GP 
DY R179 
1KR2F-3-GP 
DY 
1 2
C165 
SCD1U10V2KX-5GP 
C165 
SCD1U10V2KX-5GP 
1 2
R163 
2R2010J-1-GP 
R163 
2R2010J-1-GP 
1 2
C187 
SCD1U10V2KX-5GP 
C187 
SCD1U10V2KX-5GP 
1 2
C167 SCD01U50V2KX-1GP C167 SCD01U50V2KX-1GP 1 2
R156 
10KR2F-2-GP 
R156 
10KR2F-2-GP 
1 2
S
S
S
G D
D
D
D
Q9 
AO4406AL-GP 
S
S
S
G D
D
D
D
Q9 
AO4406AL-GP 
1
2
3
4 5
6
7
8
R175 
2R2010J-1-GP 
R175 
2R2010J-1-GP 
1 2
R442 
4K7R2J-2-GP 
R442 
4K7R2J-2-GP 
1 2
R438 
4K7R2J-2-GP 
R438 
4K7R2J-2-GP 
1 2
R493 
1KR2F-3-GP 
R493 
1KR2F-3-GP 
1 2
F11 
POLYSW-2A6V-4-GP 
DY F11 
POLYSW-2A6V-4-GP 
DY 1 2
C181 
SCD1U10V2KX-5GP 
C181 
SCD1U10V2KX-5GP 
1 2
C171 
SCD1U10V2KX-5GP 
C171 
SCD1U10V2KX-5GP 
1 2
C166 SCD01U50V2KX-1GP C166 SCD01U50V2KX-1GP 1 2
Q10 
2N7002DW-7F-GP 
Q10 
2N7002DW-7F-GP 
1
2
3 4
5
6
R161 
2R2010J-1-GP 
R161 
2R2010J-1-GP 
1 2
R178 
2R2010J-1-GP 
R178 
2R2010J-1-GP 
1 2
F12 
FUSE-3A15V-GP 
DY F12 
FUSE-3A15V-GP 
DY 12
R170 
10KR2F-2-GP 
R170 
10KR2F-2-GP 
1 2
C182 SCD01U50V2KX-1GP C182 SCD01U50V2KX-1GP 1 2
C185 SCD01U50V2KX-1GP C185 SCD01U50V2KX-1GP 1 2
C184 SCD01U50V2KX-1GP C184 SCD01U50V2KX-1GP 1 2
R160 
0R2J-2-GP 
R160 
0R2J-2-GP 
1 2
R157 
402R2F-GP 
R157 
402R2F-GP 
1 2
U15 
74LVC1G08GW-1-GP 
U15 
74LVC1G08GW-1-GP 
B1
A2
GND 3 Y 4
VCC 5
R439 
4K7R2J-2-GP 
R439 
4K7R2J-2-GP 
1 2
S
S
S
G D
D
D
D
U14 
P2003EVG-GP 
S
S
S
G D
D
D
D
U14 
P2003EVG-GP 
1
2
3
4 5
6
7
8
R522 
0R0805-PAD-2-GP 
R522 
0R0805-PAD-2-GP 
1 2
R169 
0R2J-2-GP 
R169 
0R2J-2-GP 
1 2
R520 
0R0805-PAD-2-GP 
R520 
0R0805-PAD-2-GP 
1 2
R443 
4K7R2J-2-GP 
R443 
4K7R2J-2-GP 
1 2
R375 
10KR2F-2-GP 
R375 
10KR2F-2-GP 
1 2



5
5
4
4
3
3
2
2
1
1
D D
C C
B B
A A
N-Channel 
P-Channel 
N-Channel 
P-Channel 
HDD6 
HDD7 
ID=12A 
RDS(on) 
=11.5m ohm 
ID=12A 
RDS(on) 
=11.5m ohm 
ID=-9A 
RDS(on) 
=20m ohm 
ID=-9A 
RDS(on) 
=20m ohm 
Ihold=1.5A 
Itrip=3.0A 
1
1
0
0
1
1
HDD6_PWR EXP_A_PWR6 
OFF 
OFF 
OFF 
EXP_B_PWR6 
ON 
0
0
1
1
0
0
1
1
HDD7_PWR EXP_A_PWR7 
OFF 
OFF 
OFF 
EXP_B_PWR7 
ON 
0
0
1
1
0
0
1
1
HDD6_FLT_LED EXP_A_HDD6_FLT 
ON 
ON 
ON 
EXP_B_HDD6_FLT 
OFF 
0
0
1
1
0
0
1
1
HDD7_FLT_LED EXP_A_HDD7_FLT 
ON 
ON 
ON 
EXP_B_HDD7_FLT 
OFF 
0
0
Ihold=3A 
Itrip=6A 
Ihold=3A 
Itrip=6A 
Ihold=2A 
Itrip=4A 
EVT-3R 
20120620 
EVT-3R 
20120620 
DVT 
20120630 
DVT 
20120630 
DVT 
20120630 
BLUE VF=2.9V 
I=4.7mA 
BLUE VF=2.9V 
I=4.7mA 
AND GATE 
AND GATE 
AND GATE 
AND GATE 
DVT 
20120710 
DVT 
20120710 
RED VF=1.8V 
I=4.5mA 
RED VF=1.8V 
I=4.5mA 
DVT 
20120703 
DVT 
20120703 
DVT 
20120703 
DVT 
20120703 
DVT 
20120710 
DVT 
20120710 
DVT 
20120710 
DVT 
20120710 
DVT 
20120710 
DVT 
20120710 
DVT 
20120712 
DVT 
20120712 
DVT 
20120712 
DVT 
20120712 
DVT 
20120724 
DVT 
20120724 
PVT 
20121009 
PVT 
20121009 
PVT 
20121009 
PVT 
20121009 
FLT_NET_HDD6 
12V_PRE_6 
SAS2x28_Drive_RX_N_A6 
SAS2x28_Drive_RX_P_A6 
SAS2x28_Drive_RX_N_B6 
SAS2x28_Drive_RX_P_B6 
5V_PRE_6 
DRV_ACT_NET6 
HDD_PRSNT_NET6 
DRV_ACT_6 
12V_PRE_7 
SAS2x28_Drive_RX_N_A7 
SAS2x28_Drive_RX_P_A7 
SAS2x28_Drive_RX_N_B7 
SAS2x28_Drive_RX_P_B7 
5V_PRE_7 
HDD_PRSNT_NET7 
FLT_NET_HDD7 
DRV_ACT_NET7 DRV_ACT_7 
SW_HDD6_P 
SW_PWR_R_HDD6 
SW_HDD6_N 
SW_PWR_HDD6 
SW_PWR_HDD7 
SW_HDD7_P 
SW_HDD7_N 
DRIVE_PWR6 
SW_PWR_R_HDD7 DRIVE_PWR7 
FLT_HDD6 
FLT_HDD7 
FLT_HDD6_DRIVE 
FLT_HDD7_DRIVE 
FLT_HDD6_B 
FLT_HDD7_B 
DRIVE_ACT_7 
ACT_HDD7 
ACT_HDD6 
SW_HDD6_G SW_HDD7_G 
HDD6_LED_G 
HDD7_LED_G 
DRIVE_ACT_6 
HDD6_LED_B 
HDD7_LED_B 
P5V_HDD6 
P12V_HDD6 
P3V3 
P5V_HDD7 
P12V_HDD7 
P3V3 
P12V 
P5VB 
P12V_DRIVE_6 
P12V 
P5V_DRIVE_6 
P3V3 
P5V_HDD6 
P12V_HDD6 
P5V_HDD7 
P12V_HDD7 
P12V 
P5VB 
P12V_DRIVE_7 
P12V 
P5V_DRIVE_7 
P3V3 
P3V3 
P3V3 
P3V3 
P3V3 
P5VB 
P5VB 
P3V3 
P3V3 
P3V3 
P3V3 
P12V 
P12V 
P12V 
P12V 
P5VB_HDD6_LED P3V3 
P5VB 
P3V3_HDD6_LED 
P5VB_HDD7_LED P3V3 
P5VB 
P3V3_HDD7_LED 
SAS2x28_A_HDD6_FLT 12 
SAS2x28_B_HDD6_FLT 12 
SAS2x28_A_HDD6_TX_+ 12 
SAS2x28_A_HDD6_TX_- 12 
SAS2x28_A_HDD6_RX_- 12 
SAS2x28_A_HDD6_RX_+ 12 
SAS2x28_B_HDD6_RX_- 12 
SAS2x28_B_HDD6_RX_+ 12 
HDD_PRSNT6 13 
SAS2x28_B_HDD6_TX_+ 12 
SAS2x28_B_HDD6_TX_- 12 
SAS2x28_A_HDD7_TX_+ 12 
SAS2x28_A_HDD7_TX_- 12 
SAS2x28_A_HDD7_RX_- 12 
SAS2x28_A_HDD7_RX_+ 12 
SAS2x28_B_HDD7_TX_+ 12 
SAS2x28_B_HDD7_TX_- 12 
SAS2x28_B_HDD7_RX_- 12 
SAS2x28_B_HDD7_RX_+ 12 
HDD_PRSNT7 13 
SAS2x28_A_HDD7_FLT 12 
SAS2x28_B_HDD7_FLT 12 
SAS_EXP_A_PWR7 13 
SAS_EXP_B_PWR7 13 
SAS_EXP_A_PWR6 13 
SAS_EXP_B_PWR6 13 
Title 
Size Document Number Rev 
Date: Sheet 
of 
KNOX_DPB -1 
HDD CNs 6-7 
C
6 21 Thursday, October 11, 2012 
Wiwynn 
H/W R&D Dept. II 
8F,90,Sec. 1,Hsin Tai Wu Rd, 
Hsichih, Taipei Hsien 221, Taiwan, R.O.C 
Title 
Size Document Number Rev 
Date: Sheet 
of 
KNOX_DPB -1 
HDD CNs 6-7 
C
6 21 Thursday, October 11, 2012 
Wiwynn 
H/W R&D Dept. II 
8F,90,Sec. 1,Hsin Tai Wu Rd, 
Hsichih, Taipei Hsien 221, Taiwan, R.O.C 
Title 
Size Document Number Rev 
Date: Sheet 
of 
KNOX_DPB -1 
HDD CNs 6-7 
C
6 21 Thursday, October 11, 2012 
Wiwynn 
H/W R&D Dept. II 
8F,90,Sec. 1,Hsin Tai Wu Rd, 
Hsichih, Taipei Hsien 221, Taiwan, R.O.C 
LED8 
LED-RB-4-GP 
LED8 
LED-RB-4-GP 
1
3 2
4
C211 
SC1U25V3KX-1-GP 
C211 
SC1U25V3KX-1-GP 
1 2
R497 
1KR2F-3-GP 
R497 
1KR2F-3-GP 
1 2
R524 
0R0805-PAD-2-GP 
R524 
0R0805-PAD-2-GP 
1 2
R449 
4K7R2J-2-GP 
R449 
4K7R2J-2-GP 
1 2
R184 
10KR2F-2-GP 
R184 
10KR2F-2-GP 
1 2
R526 
0R0805-PAD-2-GP 
R526 
0R0805-PAD-2-GP 
1 2
R190 
2R2010J-1-GP 
R190 
2R2010J-1-GP 
1 2
C225 
SC10U25V6KX-1GP 
C225 
SC10U25V6KX-1GP 
1 2
C223 
SC10U25V6KX-1GP 
C223 
SC10U25V6KX-1GP 
1 2
R188 
0R2J-2-GP 
R188 
0R2J-2-GP 
1 2
R193 
4K7R2J-2-GP 
R193 
4K7R2J-2-GP 
1 2
R199 
402R2F-GP 
R199 
402R2F-GP 
1 2
R189 
4K7R2J-2-GP 
R189 
4K7R2J-2-GP 
1 2
C204 
SCD01U50V2KX-1GP 
C204 
SCD01U50V2KX-1GP 
1 2
C206 
SC10U16V6KX-2GP 
C206 
SC10U16V6KX-2GP 
1 2
C210 
SC10U25V6KX-1GP 
C210 
SC10U25V6KX-1GP 
1 2
Q14 
2N7002DW-7F-GP 
Q14 
2N7002DW-7F-GP 1
2
3 4
5
6
R378 
0R2J-2-GP 
R378 
0R2J-2-GP 
1 2
C199 SCD01U50V2KX-1GP C199 SCD01U50V2KX-1GP 1 2
C208 
SC10U25V6KX-1GP 
C208 
SC10U25V6KX-1GP 
1 2
R185 
402R2F-GP 
R185 
402R2F-GP 
1 2
C215 SCD01U50V2KX-1GP C215 SCD01U50V2KX-1GP 1 2
R377 
10KR2F-2-GP 
R377 
10KR2F-2-GP 
1 2
Q58 
2N7002DW-7F-GP 
Q58 
2N7002DW-7F-GP 
1
2
34
5
6
R207 
4K7R2J-2-GP 
R207 
4K7R2J-2-GP 
1 2
C217 SCD01U50V2KX-1GP C217 SCD01U50V2KX-1GP 1 2
C216 SCD01U50V2KX-1GP C216 SCD01U50V2KX-1GP 1 2
C219 
SCD1U10V2KX-5GP 
C219 
SCD1U10V2KX-5GP 
1 2
R208 
220R3F-1-GP 
R208 
220R3F-1-GP 
1 2
LED7 
LED-RB-4-GP 
LED7 
LED-RB-4-GP 
1
3 2
4
R446 
4K7R2J-2-GP 
R446 
4K7R2J-2-GP 
1 2
S
S
S
G D
D
D
D
Q13 
AO4406AL-GP 
S
S
S
G D
D
D
D
Q13 
AO4406AL-GP 
1
2
3
4 5
6
7
8
R206 
1KR2F-3-GP 
DY R206 
1KR2F-3-GP 
DY 
1 2
C197 
SCD1U10V2KX-5GP 
C197 
SCD1U10V2KX-5GP 
1 2
C222 
SCD01U50V2KX-1GP 
C222 
SCD01U50V2KX-1GP 
1 2
Q61 
2N7002-11-GP 
Q61 
2N7002-11-GP 
G
SD
R495 
4K7R2J-2-GP 
R495 
4K7R2J-2-GP 
1 2
R451 
4K7R2J-2-GP 
R451 
4K7R2J-2-GP 
1 2
S
S
S
G D
D
D
D
U20 
P2003EVG-GP 
S
S
S
G D
D
D
D
U20 
P2003EVG-GP 
1
2
3
4 5
6
7
8
R196 
0R2J-2-GP 
R196 
0R2J-2-GP 
1 2
R525 
0R1206-PAD-1-GP 
R525 
0R1206-PAD-1-GP 
1 2
Q59 
2N7002-11-GP 
Q59 
2N7002-11-GP 
G
SD
R209 
2R2010J-1-GP 
R209 
2R2010J-1-GP 
1 2
R448 
4K7R2J-2-GP 
R448 
4K7R2J-2-GP 
1 2
Q40 
PMBS3904-1-GP 
Q40 
PMBS3904-1-GP 3
1
2
R191 
220R3F-1-GP 
R191 
220R3F-1-GP 
1 2
C226 
SC10U25V6KX-1GP 
C226 
SC10U25V6KX-1GP 
1 2
C224 
SC10U25V6KX-1GP 
C224 
SC10U25V6KX-1GP 
1 2
C214 SCD01U50V2KX-1GP C214 SCD01U50V2KX-1GP 1 2
R194 
4K7R2J-2-GP 
R194 
4K7R2J-2-GP 
1 2
F14 
FUSE-3A15V-GP 
DY F14 
FUSE-3A15V-GP 
DY 12
C213 
SCD1U10V2KX-5GP 
C213 
SCD1U10V2KX-5GP 
1 2
S
S
S
G D
D
D
D
Q15 
AO4406AL-GP 
S
S
S
G D
D
D
D
Q15 
AO4406AL-GP 
1
2
3
4 5
6
7
8
U21 
74LVC1G08GW-1-GP 
U21 
74LVC1G08GW-1-GP 
B1
A2
GND 3 Y 4
VCC 5
R384 
0R2J-2-GP 
R384 
0R2J-2-GP 
1 2
R200 
0R2J-2-GP 
R200 
0R2J-2-GP 
1 2
C200 SCD01U50V2KX-1GP C200 SCD01U50V2KX-1GP 1 2
R192 
1KR2F-3-GP 
DY R192 
1KR2F-3-GP 
DY 
1 2
TP32TPAD32-GP TP32TPAD32-GP 1
U19 
74LVC1G08GW-1-GP 
U19 
74LVC1G08GW-1-GP 
B 1
A 2
GND 3Y4
VCC 5
R205 
2R2010J-1-GP 
R205 
2R2010J-1-GP 
1 2
R197 
0R2J-2-GP 
R197 
0R2J-2-GP 
1 2
C221 
SC10U16V6KX-2GP 
C221 
SC10U16V6KX-2GP 
1 2
R195 
2R2010J-1-GP 
R195 
2R2010J-1-GP 
1 2
R383 
10KR2F-2-GP 
R383 
10KR2F-2-GP 
1 2
C227 
SC1U25V3KX-1-GP 
C227 
SC1U25V3KX-1-GP 
1 2
R527 
0R1206-PAD-1-GP 
R527 
0R1206-PAD-1-GP 
1 2
R415 
0R2J-2-GP 
R415 
0R2J-2-GP 
1 2
S
S
S
G D
D
D
D
U23 
P2003EVG-GP 
S
S
S
G D
D
D
D
U23 
P2003EVG-GP 
1
2
3
4 5
6
7
8
F13 
POLYSW-2A6V-4-GP 
DY F13 
POLYSW-2A6V-4-GP 
DY 1 2
U22 
74LVC1G08GW-1-GP 
U22 
74LVC1G08GW-1-GP 
B 1
A 2
GND 3Y4
VCC 5
C209 
SC10U25V6KX-1GP 
C209 
SC10U25V6KX-1GP 
1 2
C220 
SC1U16V3KX-5GP 
C220 
SC1U16V3KX-5GP 
1 2
C203 
SCD1U10V2KX-5GP 
C203 
SCD1U10V2KX-5GP 
1 2
R414 
0R2J-2-GP 
R414 
0R2J-2-GP 
1 2
R186 
0R2J-2-GP 
R186 
0R2J-2-GP 
1 2
C201 SCD01U50V2KX-1GP C201 SCD01U50V2KX-1GP 1 2
Q41 
PMBS3904-1-GP 
Q41 
PMBS3904-1-GP 3
1
2
Q16 
2N7002DW-7F-GP 
Q16 
2N7002DW-7F-GP 
1
2
3 4
5
6
R496 
1KR2F-3-GP 
R496 
1KR2F-3-GP 
1 2
C207 
SC10U25V6KX-1GP 
C207 
SC10U25V6KX-1GP 
1 2
C198 SCD01U50V2KX-1GP C198 SCD01U50V2KX-1GP 1 2
R211 
0R2J-2-GP 
R211 
0R2J-2-GP 
1 2
R201 
330R2F-GP 
R201 
330R2F-GP 
1 2
R447 
4K7R2J-2-GP 
R447 
4K7R2J-2-GP 
1 2
R204 
4K7R2J-2-GP 
R204 
4K7R2J-2-GP 
1 2
R203 
4K7R2J-2-GP 
R203 
4K7R2J-2-GP 
1 2
SKT7 
SKT-SATA14P-15P-12-GP 
SKT7 
SKT-SATA14P-15P-12-GP 
S1 
S2 
S3 
S4 
S5 
S6 
S7 
S8 
S9 
S10 
S11 
S12 
S13 
S14 
P1 
P2 
P3 
P4 
P5 
P6 
P7 
P8 
P9 
P10 
P11 
P12 
P13 
P14 
NP2 
NP1 
P15 
H2 
H1 
R210 
0R2J-2-GP 
R210 
0R2J-2-GP 
1 2
F15 
POLYSW-2A6V-4-GP 
DY F15 
POLYSW-2A6V-4-GP 
DY 1 2
Q60 
2N7002DW-7F-GP 
Q60 
2N7002DW-7F-GP 
1
2
34
5
6
R187 
330R2F-GP 
R187 
330R2F-GP 
1 2
C205 
SC1U16V3KX-5GP 
C205 
SC1U16V3KX-5GP 
1 2
SKT8 
SKT-SATA14P-15P-12-GP 
SKT8 
SKT-SATA14P-15P-12-GP 
S1 
S2 
S3 
S4 
S5 
S6 
S7 
S8 
S9 
S10 
S11 
S12 
S13 
S14 
P1 
P2 
P3 
P4 
P5 
P6 
P7 
P8 
P9 
P10 
P11 
P12 
P13 
P14 
NP2 
NP1 
P15 
H2 
H1 
R450 
4K7R2J-2-GP 
R450 
4K7R2J-2-GP 
1 2 F16 
FUSE-3A15V-GP 
DY F16 
FUSE-3A15V-GP 
DY 12
R198 
10KR2F-2-GP 
R198 
10KR2F-2-GP 
1 2
U24 
74LVC1G08GW-1-GP 
U24 
74LVC1G08GW-1-GP 
B1
A2
GND 3 Y 4
VCC 5
TP31TPAD32-GP TP31TPAD32-GP 1
R202 
0R2J-2-GP 
R202 
0R2J-2-GP 
1 2
R494 
4K7R2J-2-GP 
R494 
4K7R2J-2-GP 
1 2



5
5
4
4
3
3
2
2
1
1
D D
C C
B B
A A
N-Channel 
P-Channel 
N-Channel 
P-Channel 
HDD8 
HDD9 
ID=12A 
RDS(on) 
=11.5m ohm 
ID=12A 
RDS(on) 
=11.5m ohm 
ID=-9A 
RDS(on) 
=20m ohm 
ID=-9A 
RDS(on) 
=20m ohm 
Ihold=1.5A 
Itrip=3.0A 
1
1
0
0
1
1
HDD9_PWR EXP_A_PWR9 
OFF 
OFF 
OFF 
EXP_B_PWR9 
ON 
0
0
1
1
0
0
1
1
HDD8_FLT_LED EXP_A_HDD8_FLT 
ON 
ON 
ON 
EXP_B_HDD8_FLT 
OFF 
0
0
1
1
0
0
1
1
HDD9_FLT_LED EXP_A_HDD9_FLT 
ON 
ON 
ON 
EXP_B_HDD9_FLT 
OFF 
0
0
1
1
0
0
1
1
HDD8_PWR EXP_A_PWR8 
OFF 
OFF 
OFF 
EXP_B_PWR8 
ON 
0
0
Ihold=3A 
Itrip=6A 
Ihold=3A 
Itrip=6A 
Ihold=2A 
Itrip=4A 
EVT-3R 
20120620 
EVT-3R 
20120620 
DVT 
20120630 
DVT 
20120630 
BLUE VF=2.9V 
I=4.7mA 
BLUE VF=2.9V 
I=4.7mA 
AND GATE 
AND GATE 
AND GATE 
AND GATE 
DVT 
20120710 
DVT 
20120710 
RED VF=1.8V 
I=4.5mA 
RED VF=1.8V 
I=4.5mA 
DVT 
20120703 
DVT 
20120703 
DVT 
20120703 
DVT 
20120703 
DVT 
20120710 
DVT 
20120710 
DVT 
20120710 
DVT 
20120710 
DVT 
20120710 
DVT 
20120710 
DVT 
20120712 
DVT 
20120712 
DVT 
20120712 
DVT 
20120712 
DVT 
20120724 
DVT 
20120724 
PVT 
20121009 
PVT 
20121009 
PVT 
20121009 
PVT 
20121009 
FLT_NET_HDD9 
12V_PRE_9 
SAS2x28_Drive_RX_N_A9 
SAS2x28_Drive_RX_P_A9 
SAS2x28_Drive_RX_N_B9 
SAS2x28_Drive_RX_P_B9 
5V_PRE_9 
DRV_ACT_NET9 
FLT_HDD9 
DRV_ACT_9 
12V_PRE_8 
SAS2x28_Drive_RX_N_A8 
SAS2x28_Drive_RX_P_A8 
SAS2x28_Drive_RX_N_B8 
SAS2x28_Drive_RX_P_B8 
5V_PRE_8 
FLT_NET_HDD8 
DRV_ACT_NET8 DRV_ACT_8 
SW_PWR_R_HDD8 
SW_PWR_HDD9 
SW_HDD9_P 
SW_PWR_R_HDD9 
SW_HDD9_N 
DRIVE_PWR8 
DRIVE_PWR9 
SW_HDD8_P 
SW_HDD8_N 
FLT_HDD8 FLT_HDD8_DRIVE 
FLT_HDD9_DRIVE 
SW_PWR_HDD8 
FLT_HDD8_B 
DRIVE_ACT_8 
FLT_HDD9_B 
DRIVE_ACT_9 
ACT_HDD8 
ACT_HDD9 
SW_HDD8_G 
HDD8_LED_G 
HDD9_LED_G 
SW_HDD9_G 
HDD_PRSNT_NET9 
HDD8_LED_B 
HDD9_LED_B 
HDD_PRSNT_NET8 
P5V_HDD9 
P12V_HDD9 
P3V3 
P5V_HDD8 
P12V_HDD8 P3V3 
P5V_HDD8 
P12V_HDD8 
P12V 
P5VB 
P12V_DRIVE_8 
P12V 
P5V_DRIVE_8 
P3V3 
P5V_HDD9 
P12V_HDD9 
P12V 
P5VB 
P12V_DRIVE_9 
P12V 
P5V_DRIVE_9 
P3V3 
P3V3 
P3V3 
P3V3 
P3V3 
P5VB 
P5VB 
P3V3 
P3V3 
P3V3 
P3V3 
P12V 
P12V 
P12V 
P12V 
P5VB_HDD8_LED P3V3 
P5VB 
P3V3_HDD8_LED 
P5VB_HDD9_LED P3V3 
P5VB 
P3V3_HDD9_LED 
SAS2x28_A_HDD9_FLT 12 
SAS2x28_B_HDD9_FLT 12 
SAS2x28_A_HDD9_TX_+ 12 
SAS2x28_A_HDD9_TX_- 12 
SAS2x28_A_HDD9_RX_- 12 
SAS2x28_A_HDD9_RX_+ 12 
SAS2x28_B_HDD9_TX_+ 12 
SAS2x28_B_HDD9_TX_- 12 
SAS2x28_B_HDD9_RX_- 12 
SAS2x28_B_HDD9_RX_+ 12 
HDD_PRSNT9 13 
SAS2x28_A_HDD8_TX_+ 12 
SAS2x28_A_HDD8_TX_- 12 
SAS2x28_A_HDD8_RX_- 12 
SAS2x28_A_HDD8_RX_+ 12 
SAS2x28_B_HDD8_TX_+ 12 
SAS2x28_B_HDD8_TX_- 12 
SAS2x28_B_HDD8_RX_- 12 
SAS2x28_B_HDD8_RX_+ 12 
HDD_PRSNT8 13 
SAS2x28_A_HDD8_FLT 12 
SAS2x28_B_HDD8_FLT 12 
SAS_EXP_A_PWR8 13 
SAS_EXP_B_PWR8 13 
SAS_EXP_A_PWR9 13 
SAS_EXP_B_PWR9 13 
Title 
Size Document Number Rev 
Date: Sheet 
of 
KNOX_DPB -1 
HDD CNs 8-9 
C
7 21 Thursday, October 11, 2012 
Wiwynn 
H/W R&D Dept. II 
8F,90,Sec. 1,Hsin Tai Wu Rd, 
Hsichih, Taipei Hsien 221, Taiwan, R.O.C 
Title 
Size Document Number Rev 
Date: Sheet 
of 
KNOX_DPB -1 
HDD CNs 8-9 
C
7 21 Thursday, October 11, 2012 
Wiwynn 
H/W R&D Dept. II 
8F,90,Sec. 1,Hsin Tai Wu Rd, 
Hsichih, Taipei Hsien 221, Taiwan, R.O.C 
Title 
Size Document Number Rev 
Date: Sheet 
of 
KNOX_DPB -1 
HDD CNs 8-9 
C
7 21 Thursday, October 11, 2012 
Wiwynn 
H/W R&D Dept. II 
8F,90,Sec. 1,Hsin Tai Wu Rd, 
Hsichih, Taipei Hsien 221, Taiwan, R.O.C 
Q62 
2N7002DW-7F-GP 
Q62 
2N7002DW-7F-GP 
1
2
34
5
6
R234 
2R2010J-1-GP 
R234 
2R2010J-1-GP 
1 2
Q43 
PMBS3904-1-GP 
Q43 
PMBS3904-1-GP 3
1
2
R229 
330R2F-GP 
R229 
330R2F-GP 
1 2
S
S
S
G D
D
D
D
Q19 
AO4406AL-GP 
S
S
S
G D
D
D
D
Q19 
AO4406AL-GP 
1
2
3
4 5
6
7
8
C251 
SC10U16V6KX-2GP 
C251 
SC10U16V6KX-2GP 
1 2
R416 
0R2J-2-GP 
R416 
0R2J-2-GP 
1 2
Q65 
2N7002-11-GP 
Q65 
2N7002-11-GP 
G
SD
C233 SCD01U50V2KX-1GP C233 SCD01U50V2KX-1GP 1 2
R227 
402R2F-GP 
R227 
402R2F-GP 
1 2
R529 
0R1206-PAD-1-GP 
R529 
0R1206-PAD-1-GP 
1 2
U25 
74LVC1G08GW-1-GP 
U25 
74LVC1G08GW-1-GP 
B 1
A 2
GND 3Y4
VCC 5
R394 
0R2J-2-GP 
R394 
0R2J-2-GP 
1 2
R230 
0R2J-2-GP 
R230 
0R2J-2-GP 
1 2
R455 
4K7R2J-2-GP 
R455 
4K7R2J-2-GP 
1 2
U30 
74LVC1G08GW-1-GP 
U30 
74LVC1G08GW-1-GP 
B1
A2
GND 3 Y 4
VCC 5
R498 
1KR2F-3-GP 
R498 
1KR2F-3-GP 
1 2
R218 
2R2010J-1-GP 
R218 
2R2010J-1-GP 
1 2
S
S
S
G D
D
D
D
Q17 
AO4406AL-GP 
S
S
S
G D
D
D
D
Q17 
AO4406AL-GP 
1
2
3
4 5
6
7
8
R395 
10KR2F-2-GP 
R395 
10KR2F-2-GP 
1 2
U27 
74LVC1G08GW-1-GP 
U27 
74LVC1G08GW-1-GP 
B1
A2
GND 3 Y 4
VCC 5
C254 
SCD01U50V2KX-1GP 
C254 
SCD01U50V2KX-1GP 
1 2
R224 
0R2J-2-GP 
R224 
0R2J-2-GP 
1 2
R215 
330R2F-GP 
R215 
330R2F-GP 
1 2
C243 
SC1U25V3KX-1-GP 
C243 
SC1U25V3KX-1-GP 
1 2
TP34TPAD32-GP TP34TPAD32-GP 1
R235 
4K7R2J-2-GP 
R235 
4K7R2J-2-GP 
1 2
R452 
4K7R2J-2-GP 
R452 
4K7R2J-2-GP 
1 2
C256 
SC10U25V6KX-1GP 
C256 
SC10U25V6KX-1GP 
1 2
R222 
4K7R2J-2-GP 
R222 
4K7R2J-2-GP 
1 2
C253 
SCD1U10V2KX-5GP 
C253 
SCD1U10V2KX-5GP 
1 2
R459 
4K7R2J-2-GP 
R459 
4K7R2J-2-GP 
1 2
C247 SCD01U50V2KX-1GP C247 SCD01U50V2KX-1GP 1 2
C231 SCD01U50V2KX-1GP C231 SCD01U50V2KX-1GP 1 2
LED10 
LED-RB-4-GP 
LED10 
LED-RB-4-GP 
1
3 2
4
C255 
SC10U25V6KX-1GP 
C255 
SC10U25V6KX-1GP 
1 2
R417 
0R2J-2-GP 
R417 
0R2J-2-GP 
1 2
R225 
0R2J-2-GP 
R225 
0R2J-2-GP 
1 2
R223 
2R2010J-1-GP 
R223 
2R2010J-1-GP 
1 2
C242 
SC10U25V6KX-1GP 
C242 
SC10U25V6KX-1GP 
1 2
R528 
0R0805-PAD-2-GP 
R528 
0R0805-PAD-2-GP 
1 2
R217 
4K7R2J-2-GP 
R217 
4K7R2J-2-GP 
1 2
TP33 
TPAD32-GP 
TP33 
TPAD32-GP 
1
R216 
0R2J-2-GP 
R216 
0R2J-2-GP 
1 2
LED9 
LED-RB-4-GP 
LED9 
LED-RB-4-GP 
1
3 2
4
R530 
0R0805-PAD-2-GP 
R530 
0R0805-PAD-2-GP 
1 2
R531 
0R1206-PAD-1-GP 
R531 
0R1206-PAD-1-GP 
1 2
R213 
402R2F-GP 
R213 
402R2F-GP 
1 2
R226 
10KR2F-2-GP 
R226 
10KR2F-2-GP 
1 2
C230 SCD01U50V2KX-1GP C230 SCD01U50V2KX-1GP 1 2 C241 
SC10U25V6KX-1GP 
C241 
SC10U25V6KX-1GP 
1 2
Q18 
2N7002DW-7F-GP 
Q18 
2N7002DW-7F-GP 
1
2
3 4
5
6
R232 
4K7R2J-2-GP 
R232 
4K7R2J-2-GP 
1 2
S
S
S
G D
D
D
D
U29 
P2003EVG-GP 
S
S
S
G D
D
D
D
U29 
P2003EVG-GP 
1
2
3
4 5
6
7
8
R456 
4K7R2J-2-GP 
R456 
4K7R2J-2-GP 
1 2
R219 
220R3F-1-GP 
R219 
220R3F-1-GP 
1 2
R231 
1KR2F-3-GP 
DY R231 
1KR2F-3-GP 
DY 
1 2
R237 
220R3F-1-GP 
R237 
220R3F-1-GP 
1 2
S
S
S
G D
D
D
D
U26 
P2003EVG-GP 
S
S
S
G D
D
D
D
U26 
P2003EVG-GP 
1
2
3
4 5
6
7
8
U28 
74LVC1G08GW-1-GP 
U28 
74LVC1G08GW-1-GP 
B 1
A 2
GND 3Y4
VCC 5
R212 
10KR2F-2-GP 
R212 
10KR2F-2-GP 
1 2
C235 
SCD1U10V2KX-5GP 
C235 
SCD1U10V2KX-5GP 
1 2
R499 
1KR2F-3-GP 
R499 
1KR2F-3-GP 
1 2
R454 
4K7R2J-2-GP 
R454 
4K7R2J-2-GP 
1 2
R238 
0R2J-2-GP 
R238 
0R2J-2-GP 
1 2
C237 
SC10U16V6KX-2GP 
C237 
SC10U16V6KX-2GP 
1 2
R239 
0R2J-2-GP 
R239 
0R2J-2-GP 
1 2
C248 SCD01U50V2KX-1GP C248 SCD01U50V2KX-1GP 1 2
Q42 
PMBS3904-1-GP 
Q42 
PMBS3904-1-GP 3
1
2
R236 
2R2010J-1-GP 
R236 
2R2010J-1-GP 
1 2
C236 
SC1U16V3KX-5GP 
C236 
SC1U16V3KX-5GP 
1 2
C258 
SC10U25V6KX-1GP 
C258 
SC10U25V6KX-1GP 
1 2
F20 
FUSE-3A15V-GP 
DY F20 
FUSE-3A15V-GP 
DY 12
R221 
4K7R2J-2-GP 
R221 
4K7R2J-2-GP 
1 2
R458 
4K7R2J-2-GP 
R458 
4K7R2J-2-GP 
1 2
Q63 
2N7002-11-GP 
Q63 
2N7002-11-GP 
G
SD
F18 
FUSE-3A15V-GP 
DY F18 
FUSE-3A15V-GP 
DY 12
C246 SCD01U50V2KX-1GP C246 SCD01U50V2KX-1GP 1 2
R453 
4K7R2J-2-GP 
R453 
4K7R2J-2-GP 
1 2
C257 
SC10U25V6KX-1GP 
C257 
SC10U25V6KX-1GP 
1 2
F19 
POLYSW-2A6V-4-GP 
DY F19 
POLYSW-2A6V-4-GP 
DY 1 2
R220 
1KR2F-3-GP 
DY R220 
1KR2F-3-GP 
DY 
1 2
R228 
0R2J-2-GP 
R228 
0R2J-2-GP 
1 2
C249 SCD01U50V2KX-1GP C249 SCD01U50V2KX-1GP 1 2
F17 
POLYSW-2A6V-4-GP 
DY F17 
POLYSW-2A6V-4-GP 
DY 1 2
R214 
0R2J-2-GP 
R214 
0R2J-2-GP 
1 2
SKT9 
SKT-SATA14P-15P-12-GP 
SKT9 
SKT-SATA14P-15P-12-GP 
S1 
S2 
S3 
S4 
S5 
S6 
S7 
S8 
S9 
S10 
S11 
S12 
S13 
S14 
P1 
P2 
P3 
P4 
P5 
P6 
P7 
P8 
P9 
P10 
P11 
P12 
P13 
P14 
NP2 
NP1 
P15 
H2 
H1 
SKT10 
SKT-SATA14P-15P-12-GP 
SKT10 
SKT-SATA14P-15P-12-GP 
S1 
S2 
S3 
S4 
S5 
S6 
S7 
S8 
S9 
S10 
S11 
S12 
S13 
S14 
P1 
P2 
P3 
P4 
P5 
P6 
P7 
P8 
P9 
P10 
P11 
P12 
P13 
P14 
NP2 
NP1 
P15 
H2 
H1 
Q20 
2N7002DW-7F-GP 
Q20 
2N7002DW-7F-GP 
1
2
3 4
5
6
C229 
SCD1U10V2KX-5GP 
C229 
SCD1U10V2KX-5GP 
1 2
Q64 
2N7002DW-7F-GP 
Q64 
2N7002DW-7F-GP 
1
2
34
5
6
C240 
SC10U25V6KX-1GP 
C240 
SC10U25V6KX-1GP 
1 2
R385 
10KR2F-2-GP 
R385 
10KR2F-2-GP 
1 2
C250 
SC1U16V3KX-5GP 
C250 
SC1U16V3KX-5GP 
1 2
C238 
SCD01U50V2KX-1GP 
C238 
SCD01U50V2KX-1GP 
1 2
C259 
SC1U25V3KX-1-GP 
C259 
SC1U25V3KX-1-GP 
1 2
C245 
SCD1U10V2KX-5GP 
C245 
SCD1U10V2KX-5GP 
1 2
C239 
SC10U25V6KX-1GP 
C239 
SC10U25V6KX-1GP 
1 2
C232 SCD01U50V2KX-1GP C232 SCD01U50V2KX-1GP 1 2
R393 
0R2J-2-GP 
R393 
0R2J-2-GP 
1 2
R233 
4K7R2J-2-GP 
R233 
4K7R2J-2-GP 
1 2
R457 
4K7R2J-2-GP 
R457 
4K7R2J-2-GP 
1 2



5
5
4
4
3
3
2
2
1
1
D D
C C
B B
A A
N-Channel 
P-Channel 
N-Channel 
P-Channel 
HDD10 
HDD11 
ID=12A 
RDS(on) 
=11.5m ohm 
ID=12A 
RDS(on) 
=11.5m ohm 
ID=-9A 
RDS(on) 
=20m ohm 
ID=-9A 
RDS(on) 
=20m ohm 
Ihold=1.5A 
Itrip=3.0A 
1
1
0
0
1
1
HDD11_PWR EXP_A_PWR11 
OFF 
OFF 
OFF 
EXP_B_PWR11 
ON 
0
0
1
1
0
0
1
1
HDD10_FLT_LED EXP_A_HDD10_FLT 
ON 
ON 
ON 
EXP_B_HDD10_FLT 
OFF 
0
0
1
1
0
0
1
1
HDD11_FLT_LED EXP_A_HDD11_FLT 
ON 
ON 
ON 
EXP_B_HDD11_FLT 
OFF 
0
0
Ihold=3A 
Itrip=6A 
Ihold=3A 
Itrip=6A 
Ihold=2A 
Itrip=4A 
EVT-3R 
20120620 
EVT-3R 
20120620 
1
1
0
0
1
1
HDD10_PWR EXP_A_PWR10 
OFF 
OFF 
OFF 
EXP_B_PWR10 
ON 
0
0
DVT 
20120630 
DVT 
20120630 
BLUE VF=2.9V 
I=4.7mA 
BLUE VF=2.9V 
I=4.7mA 
AND GATE 
AND GATE 
AND GATE 
AND GATE 
DVT 
20120710 
DVT 
20120710 
RED VF=1.8V 
I=4.5mA 
RED VF=1.8V 
I=4.5mA 
DVT 
20120703 
DVT 
20120703 
DVT 
20120703 
DVT 
20120703 
DVT 
20120710 
DVT 
20120710 
DVT 
20120710 
DVT 
20120710 
DVT 
20120710 
DVT 
20120710 
DVT 
20120712 
DVT 
20120712 
DVT 
20120712 
DVT 
20120712 
DVT 
20120724 
DVT 
20120724 
PVT 
20121009 
PVT 
20121009 
PVT 
20121009 
PVT 
20121009 
HDD_PRSNT_NET10 
DRV_ACT_10 
FLT_NET_HDD10 
12V_PRE_10 
SAS2x28_Drive_RX_N_A10 
SAS2x28_Drive_RX_P_A10 
SAS2x28_Drive_RX_N_B10 
SAS2x28_Drive_RX_P_B10 
5V_PRE_10 
DRV_ACT_NET10 
SW_PWR_HDD10 
SW_HDD10_P 
SW_PWR_R_HDD10 
SW_HDD10_N 
12V_PRE_11 
SAS2x28_Drive_RX_N_A11 
SAS2x28_Drive_RX_P_A11 
SAS2x28_Drive_RX_N_B11 
SAS2x28_Drive_RX_P_B11 
5V_PRE_11 
HDD_PRSNT_NET11 
FLT_NET_HDD11 
DRV_ACT_NET11 DRV_ACT_11 
SW_HDD11_P 
SW_HDD11_N 
DRIVE_PWR10 
DRIVE_PWR11 
FLT_HDD10 
FLT_HDD11 FLT_HDD11_DRIVE 
SW_PWR_HDD11 SW_PWR_R_HDD11 
FLT_HDD10_B 
FLT_HDD10_DRIVE 
DRIVE_ACT_10 
FLT_HDD11_B 
ACT_HDD10 
ACT_HDD11 
HDD10_LED_G 
DRIVE_ACT_11 
HDD11_LED_G 
SW_HDD10_G 
SW_HDD11_G 
HDD10_LED_B 
HDD11_LED_B 
P3V3 
P5V_HDD10 
P12V_HDD10 
P12V 
P5VC 
P12V_DRIVE_10 
P12V 
P5V_DRIVE_10 
P3V3 
P5V_HDD10 
P12V_HDD10 
P5V_HDD11 
P12V_HDD11 
P3V3 
P12V 
P5VC 
P12V_DRIVE_11 
P12V 
P5V_DRIVE_11 
P3V3 
P5V_HDD11 
P12V_HDD11 
P3V3 
P3V3 
P3V3 
P3V3 
P5VC 
P5VC 
P3V3 
P3V3 
P3V3 
P3V3 
P12V 
P12V 
P12V 
P12V 
P5VC_HDD10_LED P3V3 
P5VC 
P3V3_HDD10_LED 
P5VC_HDD11_LED P3V3 
P5VC 
P3V3_HDD11_LED 
SAS2x28_A_HDD10_FLT 12 
SAS2x28_B_HDD10_FLT 12 
SAS2x28_A_HDD10_TX_+ 12 
SAS2x28_A_HDD10_TX_- 12 
SAS2x28_A_HDD10_RX_- 12 
SAS2x28_A_HDD10_RX_+ 12 
SAS2x28_B_HDD10_TX_+ 12 
SAS2x28_B_HDD10_TX_- 12 
SAS2x28_B_HDD10_RX_- 12 
SAS2x28_B_HDD10_RX_+ 12 
HDD_PRSNT10 13 
SAS_EXP_A_PWR10 13 
SAS_EXP_B_PWR10 13 
SAS2x28_A_HDD11_TX_+ 12 
SAS2x28_A_HDD11_TX_- 12 
SAS2x28_A_HDD11_RX_- 12 
SAS2x28_A_HDD11_RX_+ 12 
SAS2x28_B_HDD11_TX_+ 12 
SAS2x28_B_HDD11_TX_- 12 
SAS2x28_B_HDD11_RX_- 12 
SAS2x28_B_HDD11_RX_+ 12 
HDD_PRSNT11 13 
SAS2x28_A_HDD11_FLT 12 
SAS2x28_B_HDD11_FLT 12 
SAS_EXP_A_PWR11 13 
SAS_EXP_B_PWR11 13 
Title 
Size Document Number Rev 
Date: Sheet 
of 
KNOX_DPB -1 
HDD CNs 10-11 
C
8 21 Thursday, October 11, 2012 
Wiwynn 
H/W R&D Dept. II 
8F,90,Sec. 1,Hsin Tai Wu Rd, 
Hsichih, Taipei Hsien 221, Taiwan, R.O.C 
Title 
Size Document Number Rev 
Date: Sheet 
of 
KNOX_DPB -1 
HDD CNs 10-11 
C
8 21 Thursday, October 11, 2012 
Wiwynn 
H/W R&D Dept. II 
8F,90,Sec. 1,Hsin Tai Wu Rd, 
Hsichih, Taipei Hsien 221, Taiwan, R.O.C 
Title 
Size Document Number Rev 
Date: Sheet 
of 
KNOX_DPB -1 
HDD CNs 10-11 
C
8 21 Thursday, October 11, 2012 
Wiwynn 
H/W R&D Dept. II 
8F,90,Sec. 1,Hsin Tai Wu Rd, 
Hsichih, Taipei Hsien 221, Taiwan, R.O.C 
R461 
4K7R2J-2-GP 
R461 
4K7R2J-2-GP 
1 2
C279 SCD01U50V2KX-1GP C279 SCD01U50V2KX-1GP 1 2
R535 
0R1206-PAD-1-GP 
R535 
0R1206-PAD-1-GP 
1 2
R500 
1KR2F-3-GP 
R500 
1KR2F-3-GP 
1 2
R255 
402R2F-GP 
R255 
402R2F-GP 
1 2
C263 SCD01U50V2KX-1GP C263 SCD01U50V2KX-1GP 1 2
C272 
SC1U25V3KX-1-GP 
C272 
SC1U25V3KX-1-GP 
1 2
R264 
2R2010J-1-GP 
R264 
2R2010J-1-GP 
1 2
F21 
POLYSW-2A6V-4-GP 
DY F21 
POLYSW-2A6V-4-GP 
DY 1 2
Q68 
2N7002DW-7F-GP 
Q68 
2N7002DW-7F-GP 
1
2
34
5
6
C275 
SC10U25V6KX-1GP 
C275 
SC10U25V6KX-1GP 
1 2
R245 
2R2010J-1-GP 
R245 
2R2010J-1-GP 
1 2
R252 
0R2J-2-GP 
R252 
0R2J-2-GP 
1 2
C266 
SC1U16V3KX-5GP 
C266 
SC1U16V3KX-5GP 
1 2
R464 
4K7R2J-2-GP 
R464 
4K7R2J-2-GP 
1 2
C262 SCD01U50V2KX-1GP C262 SCD01U50V2KX-1GP 1 2
R262 
4K7R2J-2-GP 
R262 
4K7R2J-2-GP 
1 2
R246 
4K7R2J-2-GP 
R246 
4K7R2J-2-GP 
1 2
C274 
SC10U25V6KX-1GP 
C274 
SC10U25V6KX-1GP 
1 2
R532 
0R0805-PAD-2-GP 
R532 
0R0805-PAD-2-GP 
1 2
C278 SCD01U50V2KX-1GP C278 SCD01U50V2KX-1GP 1 2
R256 
0R2J-2-GP 
R256 
0R2J-2-GP 
1 2
R254 
10KR2F-2-GP 
R254 
10KR2F-2-GP 
1 2
R250 
2R2010J-1-GP 
R250 
2R2010J-1-GP 
1 2
C288 
SC10U25V6KX-1GP 
C288 
SC10U25V6KX-1GP 
1 2
R534 
0R0805-PAD-2-GP 
R534 
0R0805-PAD-2-GP 
1 2
R249 
4K7R2J-2-GP 
R249 
4K7R2J-2-GP 
1 2
Q44 
PMBS3904-1-GP 
Q44 
PMBS3904-1-GP 3
1
2
R467 
4K7R2J-2-GP 
R467 
4K7R2J-2-GP 
1 2
R462 
4K7R2J-2-GP 
R462 
4K7R2J-2-GP 
1 2
C267 
SC10U16V6KX-2GP 
C267 
SC10U16V6KX-2GP 
1 2
C287 
SC10U25V6KX-1GP 
C287 
SC10U25V6KX-1GP 
1 2
C283 
SCD1U10V2KX-5GP 
C283 
SCD1U10V2KX-5GP 
1 2
Q67 
2N7002-11-GP 
Q67 
2N7002-11-GP 
G
SD
R240 
10KR2F-2-GP 
R240 
10KR2F-2-GP 
1 2
R398 
0R2J-2-GP 
R398 
0R2J-2-GP 
1 2
Q22 
2N7002DW-7F-GP 
Q22 
2N7002DW-7F-GP 
1
2
3 4
5
6
C270 
SCD01U50V2KX-1GP 
C270 
SCD01U50V2KX-1GP 
1 2
S
S
S
G D
D
D
D
Q23 
AO4406AL-GP 
S
S
S
G D
D
D
D
Q23 
AO4406AL-GP 
1
2
3
4 5
6
7
8
U34 
74LVC1G08GW-1-GP 
U34 
74LVC1G08GW-1-GP 
B 1
A 2
GND 3Y4
VCC 5
C291 
SC1U25V3KX-1-GP 
C291 
SC1U25V3KX-1-GP 
1 2
Q24 
2N7002DW-7F-GP 
Q24 
2N7002DW-7F-GP 
1
2
3 4
5
6
SKT11 
SKT-SATA14P-15P-12-GP 
SKT11 
SKT-SATA14P-15P-12-GP 
S1 
S2 
S3 
S4 
S5 
S6 
S7 
S8 
S9 
S10 
S11 
S12 
S13 
S14 
P1 
P2 
P3 
P4 
P5 
P6 
P7 
P8 
P9 
P10 
P11 
P12 
P13 
P14 
NP2 
NP1 
P15 
H2 
H1 
R244 
0R2J-2-GP 
R244 
0R2J-2-GP 
1 2
R241 
402R2F-GP 
R241 
402R2F-GP 
1 2
R396 
0R2J-2-GP 
R396 
0R2J-2-GP 
1 2
C277 
SCD1U10V2KX-5GP 
C277 
SCD1U10V2KX-5GP 
1 2
R265 
220R3F-1-GP 
R265 
220R3F-1-GP 
1 2
S
S
S
G D
D
D
D
Q21 
AO4406AL-GP 
S
S
S
G D
D
D
D
Q21 
AO4406AL-GP 
1
2
3
4 5
6
7
8
C286 
SCD01U50V2KX-1GP 
C286 
SCD01U50V2KX-1GP 
1 2
C284 
SC1U16V3KX-5GP 
C284 
SC1U16V3KX-5GP 
1 2
R460 
4K7R2J-2-GP 
R460 
4K7R2J-2-GP 
1 2
U33 
74LVC1G08GW-1-GP 
U33 
74LVC1G08GW-1-GP 
B1
A2
GND 3 Y 4
VCC 5
S
S
S
G D
D
D
D
U35 
P2003EVG-GP 
S
S
S
G D
D
D
D
U35 
P2003EVG-GP 
1
2
3
4 5
6
7
8
R253 
0R2J-2-GP 
R253 
0R2J-2-GP 
1 2
R266 
0R2J-2-GP 
R266 
0R2J-2-GP 
1 2
R267 
0R2J-2-GP 
R267 
0R2J-2-GP 
1 2
R399 
10KR2F-2-GP 
R399 
10KR2F-2-GP 
1 2
LED11 
LED-RB-4-GP 
LED11 
LED-RB-4-GP 
1
3 2
4
S
S
S
G D
D
D
D
U32 
P2003EVG-GP 
S
S
S
G D
D
D
D
U32 
P2003EVG-GP 
1
2
3
4 5
6
7
8
R242 
0R2J-2-GP 
R242 
0R2J-2-GP 
1 2
SKT12 
SKT-SATA14P-15P-12-GP 
SKT12 
SKT-SATA14P-15P-12-GP 
S1 
S2 
S3 
S4 
S5 
S6 
S7 
S8 
S9 
S10 
S11 
S12 
S13 
S14 
P1 
P2 
P3 
P4 
P5 
P6 
P7 
P8 
P9 
P10 
P11 
P12 
P13 
P14 
NP2 
NP1 
P15 
H2 
H1 
R533 
0R1206-PAD-1-GP 
R533 
0R1206-PAD-1-GP 
1 2
U36 
74LVC1G08GW-1-GP 
U36 
74LVC1G08GW-1-GP 
B1
A2
GND 3 Y 4
VCC 5
R263 
4K7R2J-2-GP 
R263 
4K7R2J-2-GP 
1 2
R260 
2R2010J-1-GP 
R260 
2R2010J-1-GP 
1 2
C271 
SC10U25V6KX-1GP 
C271 
SC10U25V6KX-1GP 
1 2
C269 
SCD1U10V2KX-5GP 
C269 
SCD1U10V2KX-5GP 
1 2
F23 
POLYSW-2A6V-4-GP 
DY F23 
POLYSW-2A6V-4-GP 
DY 1 2
U31 
74LVC1G08GW-1-GP 
U31 
74LVC1G08GW-1-GP 
B 1
A 2
GND 3Y4
VCC 5
C281 SCD01U50V2KX-1GP C281 SCD01U50V2KX-1GP 1 2
C280 SCD01U50V2KX-1GP C280 SCD01U50V2KX-1GP 1 2
C290 
SC10U25V6KX-1GP 
C290 
SC10U25V6KX-1GP 
1 2
R419 
0R2J-2-GP 
R419 
0R2J-2-GP 
1 2
F24 
FUSE-3A15V-GP 
DY F24 
FUSE-3A15V-GP 
DY 12
R466 
4K7R2J-2-GP 
R466 
4K7R2J-2-GP 
1 2
C261 
SCD1U10V2KX-5GP 
C261 
SCD1U10V2KX-5GP 
1 2
R418 
0R2J-2-GP 
R418 
0R2J-2-GP 
1 2
R465 
4K7R2J-2-GP 
R465 
4K7R2J-2-GP 
1 2
R261 
4K7R2J-2-GP 
R261 
4K7R2J-2-GP 
1 2
R259 
1KR2F-3-GP 
DY R259 
1KR2F-3-GP 
DY 
1 2
TP35TPAD32-GP TP35TPAD32-GP 1
C273 
SC10U25V6KX-1GP 
C273 
SC10U25V6KX-1GP 
1 2
R243 
330R2F-GP 
R243 
330R2F-GP 
1 2
C289 
SC10U25V6KX-1GP 
C289 
SC10U25V6KX-1GP 
1 2
R248 
4K7R2J-2-GP 
R248 
4K7R2J-2-GP 
1 2
R257 
330R2F-GP 
R257 
330R2F-GP 
1 2
R501 
1KR2F-3-GP 
R501 
1KR2F-3-GP 
1 2
Q66 
2N7002DW-7F-GP 
Q66 
2N7002DW-7F-GP 
1
2
34
5
6
R251 
220R3F-1-GP 
R251 
220R3F-1-GP 
1 2
R463 
4K7R2J-2-GP 
R463 
4K7R2J-2-GP 
1 2
TP36TPAD32-GP TP36TPAD32-GP 1
Q69 
2N7002-11-GP 
Q69 
2N7002-11-GP 
G
SD
Q45 
PMBS3904-1-GP 
Q45 
PMBS3904-1-GP 3
1
2
R247 
1KR2F-3-GP 
DY R247 
1KR2F-3-GP 
DY 
1 2
R258 
0R2J-2-GP 
R258 
0R2J-2-GP 
1 2
C285 
SC10U16V6KX-2GP 
C285 
SC10U16V6KX-2GP 
1 2
LED12 
LED-RB-4-GP 
LED12 
LED-RB-4-GP 
1
3 2
4
C265 SCD01U50V2KX-1GP C265 SCD01U50V2KX-1GP 1 2
R397 
10KR2F-2-GP 
R397 
10KR2F-2-GP 
1 2
F22 
FUSE-3A15V-GP 
DY F22 
FUSE-3A15V-GP 
DY 12
C264 SCD01U50V2KX-1GP C264 SCD01U50V2KX-1GP 1 2



5
5
4
4
3
3
2
2
1
1
D D
C C
B B
A A
N-Channel 
P-Channel 
N-Channel 
P-Channel 
HDD12 
HDD13 
ID=12A 
RDS(on) 
=11.5m ohm 
ID=12A 
RDS(on) 
=11.5m ohm 
ID=-9A 
RDS(on) 
=20m ohm 
ID=-9A 
RDS(on) 
=20m ohm 
1
1
0
0
1
1
HDD12_PWR EXP_A_PWR12 
OFF 
OFF 
OFF 
EXP_B_PWR12 
ON 
0
0
1
1
0
0
1
1
HDD13_PWR EXP_A_PWR13 
OFF 
OFF 
OFF 
EXP_B_PWR13 
ON 
0
0
1
1
0
0
1
1
HDD12_FLT_LED EXP_A_HDD12_FLT 
ON 
ON 
ON 
EXP_B_HDD12_FLT 
OFF 
0
0
1
1
0
0
1
1
HDD13_FLT_LED EXP_A_HDD13_FLT 
ON 
ON 
ON 
EXP_B_HDD13_FLT 
OFF 
0
0
Ihold=3A 
Itrip=6A 
Ihold=3A 
Itrip=6A 
Ihold=2A 
Itrip=4A 
Ihold=2A 
Itrip=4A 
EVT-3R 
20120620 
EVT-3R 
20120620 
DVT 
20120630 
DVT 
20120630 
BLUE VF=2.9V 
I=4.7mA 
BLUE VF=2.9V 
I=4.7mA 
AND GATE 
AND GATE 
AND GATE 
AND GATE 
DVT 
20120710 
DVT 
20120710 
RED VF=1.8V 
I=4.5mA 
RED VF=1.8V 
I=4.5mA 
DVT 
20120703 
DVT 
20120703 
DVT 
20120703 
DVT 
20120703 
DVT 
20120710 
DVT 
20120710 
DVT 
20120710 
DVT 
20120710 
DVT 
20120710 
DVT 
20120710 
DVT 
20120712 
DVT 
20120712 
DVT 
20120712 
DVT 
20120712 
DVT 
20120724 
DVT 
20120724 
PVT 
20121009 
PVT 
20121009 
PVT 
20121009 
PVT 
20121009 
DRV_ACT_12 
FLT_NET_HDD12 
12V_PRE_12 
SAS2x28_Drive_RX_N_A12 
SAS2x28_Drive_RX_P_A12 
SAS2x28_Drive_RX_N_B12 
SAS2x28_Drive_RX_P_B12 
5V_PRE_12 
DRV_ACT_NET12 
HDD_PRSNT_NET12 
SW_HDD12_P 
SW_PWR_R_HDD12 
SW_HDD12_N 
SW_PWR_HDD12 
SW_PWR_R_HDD13 SW_PWR_HDD13 
FLT_HDD13 FLT_NET_HDD13 
12V_PRE_13 
SAS2x28_Drive_RX_N_A13 
SAS2x28_Drive_RX_P_A13 
SAS2x28_Drive_RX_N_B13 
SAS2x28_Drive_RX_P_B13 
5V_PRE_13 
DRV_ACT_NET13 
HDD_PRSNT_NET13 
SW_HDD13_P 
SW_HDD13_N 
DRIVE_PWR12 
DRIVE_PWR13 
FLT_HDD12 FLT_HDD12_DRIVE 
FLT_HDD13_B 
FLT_HDD13_DRIVE 
DRV_ACT_13 
DRIVE_ACT_13 
FLT_HDD12_B 
DRIVE_ACT_12 
ACT_HDD12 
ACT_HDD13 
HDD12_LED_G 
HDD13_LED_G 
SW_HDD12_G 
SW_HDD13_G 
HDD12_LED_B 
HDD13_LED_B 
P5V_HDD12 
P12V_HDD12 
P3V3 
P12V 
P5VC 
P12V_DRIVE_12 
P12V 
P5V_DRIVE_12 
P3V3 
P5V_HDD12 
P12V_HDD12 
P12V 
P5VC 
P12V_DRIVE_13 
P12V 
P5V_DRIVE_13 
P3V3 
P5V_HDD13 
P12V_HDD13 
P3V3 
P5V_HDD13 
P12V_HDD13 
P3V3 
P3V3 
P3V3 
P5VC 
P5VC 
P3V3 
P3V3 
P3V3 
P3V3 
P12V 
P12V 
P12V 
P12V 
P5VC_HDD12_LED P3V3 
P5VC 
P3V3_HDD12_LED 
P5VC_HDD13_LED P3V3 
P5VC 
P3V3_HDD13_LED 
P3V3 
SAS2x28_A_HDD12_FLT 12 
SAS2x28_B_HDD12_FLT 12 
SAS2x28_A_HDD12_TX_+ 12 
SAS2x28_A_HDD12_TX_- 12 
SAS2x28_A_HDD12_RX_- 12 
SAS2x28_A_HDD12_RX_+ 12 
SAS2x28_B_HDD12_TX_+ 12 
SAS2x28_B_HDD12_TX_- 12 
SAS2x28_B_HDD12_RX_- 12 
SAS2x28_B_HDD12_RX_+ 12 
HDD_PRSNT12 13 
SAS_EXP_A_PWR12 13 
SAS_EXP_B_PWR12 13 
SAS_EXP_A_PWR13 13 
SAS_EXP_B_PWR13 13 
SAS2x28_A_HDD13_FLT 12 
SAS2x28_B_HDD13_FLT 12 
SAS2x28_A_HDD13_TX_+ 12 
SAS2x28_A_HDD13_TX_- 12 
SAS2x28_A_HDD13_RX_- 12 
SAS2x28_A_HDD13_RX_+ 12 
SAS2x28_B_HDD13_TX_+ 12 
SAS2x28_B_HDD13_TX_- 12 
SAS2x28_B_HDD13_RX_- 12 
SAS2x28_B_HDD13_RX_+ 12 
HDD_PRSNT13 13 
Title 
Size Document Number Rev 
Date: Sheet 
of 
KNOX_DPB -1 
HDD CNs 12-13 
C
9 21 Thursday, October 11, 2012 
Wiwynn 
H/W R&D Dept. II 
8F,90,Sec. 1,Hsin Tai Wu Rd, 
Hsichih, Taipei Hsien 221, Taiwan, R.O.C 
Title 
Size Document Number Rev 
Date: Sheet 
of 
KNOX_DPB -1 
HDD CNs 12-13 
C
9 21 Thursday, October 11, 2012 
Wiwynn 
H/W R&D Dept. II 
8F,90,Sec. 1,Hsin Tai Wu Rd, 
Hsichih, Taipei Hsien 221, Taiwan, R.O.C 
Title 
Size Document Number Rev 
Date: Sheet 
of 
KNOX_DPB -1 
HDD CNs 12-13 
C
9 21 Thursday, October 11, 2012 
Wiwynn 
H/W R&D Dept. II 
8F,90,Sec. 1,Hsin Tai Wu Rd, 
Hsichih, Taipei Hsien 221, Taiwan, R.O.C 
F28 
FUSE-3A15V-GP 
DY F28 
FUSE-3A15V-GP 
DY 12
C295 SCD01U50V2KX-1GP C295 SCD01U50V2KX-1GP 1 2
R420 
0R2J-2-GP 
R420 
0R2J-2-GP 
1 2
R421 
0R2J-2-GP 
R421 
0R2J-2-GP 
1 2
C307 
SC1U25V3KX-1-GP 
C307 
SC1U25V3KX-1-GP 
1 2
R400 
0R2J-2-GP 
R400 
0R2J-2-GP 
1 2
R470 
4K7R2J-2-GP 
R470 
4K7R2J-2-GP 
1 2
C299 
SC10U16V6KX-2GP 
C299 
SC10U16V6KX-2GP 
1 2
R503 
1KR2F-3-GP 
R503 
1KR2F-3-GP 
1 2
R273 
2R2010J-1-GP 
R273 
2R2010J-1-GP 
1 2
C315 
SCD1U10V2KX-5GP 
C315 
SCD1U10V2KX-5GP 
1 2
C303 
SCD01U50V2KX-1GP 
C303 
SCD01U50V2KX-1GP 
1 2
C293 
SCD1U10V2KX-5GP 
C293 
SCD1U10V2KX-5GP 
1 2
R284 
0R2J-2-GP 
R284 
0R2J-2-GP 
1 2
C312 SCD01U50V2KX-1GP C312 SCD01U50V2KX-1GP 1 2
R282 
10KR2F-2-GP 
R282 
10KR2F-2-GP 
1 2
S
S
S
G D
D
D
D
Q25 
AO4406AL-GP 
S
S
S
G D
D
D
D
Q25 
AO4406AL-GP 
1
2
3
4 5
6
7
8
R293 
220R3F-1-GP 
R293 
220R3F-1-GP 
1 2
R505 
4K7R2J-2-GP 
R505 
4K7R2J-2-GP 
1 2
Q46 
PMBS3904-1-GP 
Q46 
PMBS3904-1-GP 3
1
2
S
S
S
G D
D
D
D
Q27 
AO4406AL-GP 
S
S
S
G D
D
D
D
Q27 
AO4406AL-GP 
1
2
3
4 5
6
7
8
R290 
4K7R2J-2-GP 
R290 
4K7R2J-2-GP 
1 2
R278 
4K7R2J-2-GP 
R278 
4K7R2J-2-GP 
1 2
C323 
SCD01U50V2KX-1GP 
C323 
SCD01U50V2KX-1GP 
1 2
S
S
S
G D
D
D
D
U38 
P2003EVG-GP 
S
S
S
G D
D
D
D
U38 
P2003EVG-GP 
1
2
3
4 5
6
7
8
C321 
SC10U25V6KX-1GP 
C321 
SC10U25V6KX-1GP 
1 2
SKT14 
SKT-SATA14P-15P-12-GP 
SKT14 
SKT-SATA14P-15P-12-GP 
S1 
S2 
S3 
S4 
S5 
S6 
S7 
S8 
S9 
S10 
S11 
S12 
S13 
S14 
P1 
P2 
P3 
P4 
P5 
P6 
P7 
P8 
P9 
P10 
P11 
P12 
P13 
P14 
NP2 
NP1 
P15 
H2 
H1 
R472 
4K7R2J-2-GP 
R472 
4K7R2J-2-GP 
1 2
R295 
0R2J-2-GP 
R295 
0R2J-2-GP 
1 2
R268 
10KR2F-2-GP 
R268 
10KR2F-2-GP 
1 2
C297 SCD01U50V2KX-1GP C297 SCD01U50V2KX-1GP 1 2
U40 
74LVC1G08GW-1-GP 
U40 
74LVC1G08GW-1-GP 
B 1
A 2
GND 3Y4
VCC 5
R277 
1KR2F-3-GP 
DY R277 
1KR2F-3-GP 
DY 
1 2
U39 
74LVC1G08GW-1-GP 
U39 
74LVC1G08GW-1-GP 
B1
A2
GND 3 Y 4
VCC 5
C320 
SC10U25V6KX-1GP 
C320 
SC10U25V6KX-1GP 
1 2
R274 
4K7R2J-2-GP 
R274 
4K7R2J-2-GP 
1 2
C317 
SC10U16V6KX-2GP 
C317 
SC10U16V6KX-2GP 
1 2
R279 
220R3F-1-GP 
R279 
220R3F-1-GP 
1 2
R289 
2R2010J-1-GP 
R289 
2R2010J-1-GP 
1 2
R537 
0R1206-PAD-1-GP 
R537 
0R1206-PAD-1-GP 
1 2
Q73 
2N7002-11-GP 
Q73 
2N7002-11-GP 
G
SD
R294 
0R2J-2-GP 
R294 
0R2J-2-GP 
1 2
R469 
4K7R2J-2-GP 
R469 
4K7R2J-2-GP 
1 2
C294 SCD01U50V2KX-1GP C294 SCD01U50V2KX-1GP 1 2
C304 
SC10U25V6KX-1GP 
C304 
SC10U25V6KX-1GP 
1 2
C296 SCD01U50V2KX-1GP C296 SCD01U50V2KX-1GP 1 2
R538 
0R0805-PAD-2-GP 
R538 
0R0805-PAD-2-GP 
1 2
Q70 
2N7002DW-7F-GP 
Q70 
2N7002DW-7F-GP 
1
2
34
5
6
R276 
2R2010J-1-GP 
R276 
2R2010J-1-GP 
1 2
R283 
402R2F-GP 
R283 
402R2F-GP 
1 2
Q71 
2N7002-11-GP 
Q71 
2N7002-11-GP 
G
SD
C302 
SC10U25V6KX-1GP 
C302 
SC10U25V6KX-1GP 
1 2
F27 
POLYSW-2A6V-4-GP 
DY F27 
POLYSW-2A6V-4-GP 
DY 1 2
F25 
POLYSW-2A6V-4-GP 
DY F25 
POLYSW-2A6V-4-GP 
DY 1 2
U37 
74LVC1G08GW-1-GP 
U37 
74LVC1G08GW-1-GP 
B 1
A 2
GND 3Y4
VCC 5
C313 SCD01U50V2KX-1GP C313 SCD01U50V2KX-1GP 1 2
Q26 
2N7002DW-7F-GP 
Q26 
2N7002DW-7F-GP 
1
2
3 4
5
6
R502 
1KR2F-3-GP 
R502 
1KR2F-3-GP 
1 2
R471 
4K7R2J-2-GP 
R471 
4K7R2J-2-GP 
1 2
U42 
74LVC1G08GW-1-GP 
U42 
74LVC1G08GW-1-GP 
B1
A2
GND 3 Y 4
VCC 5
C311 SCD01U50V2KX-1GP C311 SCD01U50V2KX-1GP 1 2
C322 
SC1U25V3KX-1-GP 
C322 
SC1U25V3KX-1-GP 
1 2
C301 
SCD1U10V2KX-5GP 
C301 
SCD1U10V2KX-5GP 
1 2
F26 
FUSE-3A15V-GP 
DY F26 
FUSE-3A15V-GP 
DY 12
R292 
2R2010J-1-GP 
R292 
2R2010J-1-GP 
1 2
Q72 
2N7002DW-7F-GP 
Q72 
2N7002DW-7F-GP 
1
2
34
5
6
TP38TPAD32-GP TP38TPAD32-GP 1
R506 
4K7R2J-2-GP 
R506 
4K7R2J-2-GP 
1 2Q47 
PMBS3904-1-GP 
Q47 
PMBS3904-1-GP 3
1
2
R288 
4K7R2J-2-GP 
R288 
4K7R2J-2-GP 
1 2
S
S
S
G D
D
D
D
U41 
P2003EVG-GP 
S
S
S
G D
D
D
D
U41 
P2003EVG-GP 
1
2
3
4 5
6
7
8
R281 
0R2J-2-GP 
R281 
0R2J-2-GP 
1 2
R291 
4K7R2J-2-GP 
R291 
4K7R2J-2-GP 
1 2
C298 
SC1U16V3KX-5GP 
C298 
SC1U16V3KX-5GP 
1 2
R401 
10KR2F-2-GP 
R401 
10KR2F-2-GP 
1 2
R287 
1KR2F-3-GP 
DY R287 
1KR2F-3-GP 
DY 
1 2
R275 
4K7R2J-2-GP 
R275 
4K7R2J-2-GP 
1 2
R536 
0R0805-PAD-2-GP 
R536 
0R0805-PAD-2-GP 
1 2
Q28 
2N7002DW-7F-GP 
Q28 
2N7002DW-7F-GP 
1
2
3 4
5
6
LED14 
LED-RB-4-GP 
LED14 
LED-RB-4-GP 
1
3 2
4
R280 
0R2J-2-GP 
R280 
0R2J-2-GP 
1 2
C310 SCD01U50V2KX-1GP C310 SCD01U50V2KX-1GP 1 2
C319 
SC10U25V6KX-1GP 
C319 
SC10U25V6KX-1GP 
1 2
R473 
4K7R2J-2-GP 
R473 
4K7R2J-2-GP 
1 2
R285 
330R2F-GP 
R285 
330R2F-GP 
1 2
R539 
0R1206-PAD-1-GP 
R539 
0R1206-PAD-1-GP 
1 2
R272 
0R2J-2-GP 
R272 
0R2J-2-GP 
1 2
C318 
SC10U25V6KX-1GP 
C318 
SC10U25V6KX-1GP 
1 2
R403 
10KR2F-2-GP 
R403 
10KR2F-2-GP 
1 2
R269 
402R2F-GP 
R269 
402R2F-GP 
1 2
R271 
330R2F-GP 
R271 
330R2F-GP 
1 2
R468 
4K7R2J-2-GP 
R468 
4K7R2J-2-GP 
1 2
R402 
0R2J-2-GP 
R402 
0R2J-2-GP 
1 2
C309 
SCD1U10V2KX-5GP 
C309 
SCD1U10V2KX-5GP 
1 2
C306 
SC10U25V6KX-1GP 
C306 
SC10U25V6KX-1GP 
1 2
SKT13 
SKT-SATA14P-15P-12-GP 
SKT13 
SKT-SATA14P-15P-12-GP 
S1 
S2 
S3 
S4 
S5 
S6 
S7 
S8 
S9 
S10 
S11 
S12 
S13 
S14 
P1 
P2 
P3 
P4 
P5 
P6 
P7 
P8 
P9 
P10 
P11 
P12 
P13 
P14 
NP2 
NP1 
P15 
H2 
H1 
R270 
0R2J-2-GP 
R270 
0R2J-2-GP 
1 2
TP37TPAD32-GP TP37TPAD32-GP 1
R286 
0R2J-2-GP 
R286 
0R2J-2-GP 
1 2
C305 
SC10U25V6KX-1GP 
C305 
SC10U25V6KX-1GP 
1 2
C316 
SC1U16V3KX-5GP 
C316 
SC1U16V3KX-5GP 
1 2
LED13 
LED-RB-4-GP 
LED13 
LED-RB-4-GP 
1
3 2
4



5
5
4
4
3
3
2
2
1
1
D D
C C
B B
A A
N-Channel 
P-Channel 
HDD14 
ID=-9A 
RDS(on) 
=20m ohm 
ID=12A 
RDS(on) 
=11.5m ohm 
1
1
0
0
1
1
HDD14_PWR EXP_A_PWR14 
OFF 
OFF 
OFF 
EXP_B_PWR14 
ON 
0
0
1
1
0
0
1
1
HDD14_FLT_LED EXP_A_HDD14_FLT 
ON 
ON 
ON 
EXP_B_HDD14_FLT 
OFF 
0
0
Ihold=3A 
Itrip=6A 
Ihold=2A 
Itrip=4A 
EVT-3R 
20120620 
DVT 
20120630 
BLUE VF=2.9V 
I=4.7mA AND GATE 
AND GATE 
DVT 
20120710 
RED VF=1.8V 
I=4.5mA 
DVT 
20120703 
DVT 
20120703 
DVT 
20120710 
DVT 
20120710 
DVT 
20120710 
DVT 
20120712 
DVT 
20120712 
DVT 
20120724 
PVT 
20121009 
PVT 
20121009 
SAS2x28_Drive_RX_N_B14 
SAS2x28_Drive_RX_P_B14 
5V_PRE_14 
HDD_PRSNT_NET14 
12V_PRE_14 
SAS2x28_Drive_RX_N_A14 
SAS2x28_Drive_RX_P_A14 
DRV_ACT_NET14 DRV_ACT_14 
FLT_NET_HDD14 
SW_HDD14_P 
SW_PWR_R_HDD14 
SW_HDD14_N 
SW_PWR_HDD14 DRIVE_PWR14 
FLT_HDD14 
FLT_HDD14_B 
FLT_HDD14_DRIVE 
ACT_HDD14 
HDD14_LED_G 
SW_HDD14_G 
DRIVE_ACT_14 
HDD14_LED_B 
P3V3 
P12V_HDD14 
P5V_HDD14 
P5V_HDD14 
P12V_HDD14 
P12V 
P5VC 
P12V_DRIVE_14 
P12V 
P5V_DRIVE_14 
P3V3 
P3V3 
P3V3 
P5VC P3V3 
P3V3 
P12V 
P12V 
P5VC_HDD14_LED P3V3 
P5VC 
P3V3_HDD14_LED 
SAS2x28_A_HDD14_RX_- 12 
SAS2x28_A_HDD14_RX_+ 12 
SAS2x28_B_HDD14_TX_+ 12 
SAS2x28_B_HDD14_TX_- 12 
SAS2x28_B_HDD14_RX_- 12 
SAS2x28_B_HDD14_RX_+ 12 
HDD_PRSNT14 13 
SAS2x28_A_HDD14_TX_+ 12 
SAS2x28_A_HDD14_TX_- 12 
SAS2x28_A_HDD14_FLT 12 
SAS2x28_B_HDD14_FLT 12 
SAS_EXP_A_PWR14 13 
SAS_EXP_B_PWR14 13 
Title 
Size Document Number Rev 
Date: Sheet 
of 
KNOX_DPB -1 
HDD CNs 14 
C
10 21 Thursday, October 11, 2012 
Wiwynn 
H/W R&D Dept. II 
8F,90,Sec. 1,Hsin Tai Wu Rd, 
Hsichih, Taipei Hsien 221, Taiwan, R.O.C 
Title 
Size Document Number Rev 
Date: Sheet 
of 
KNOX_DPB -1 
HDD CNs 14 
C
10 21 Thursday, October 11, 2012 
Wiwynn 
H/W R&D Dept. II 
8F,90,Sec. 1,Hsin Tai Wu Rd, 
Hsichih, Taipei Hsien 221, Taiwan, R.O.C 
Title 
Size Document Number Rev 
Date: Sheet 
of 
KNOX_DPB -1 
HDD CNs 14 
C
10 21 Thursday, October 11, 2012 
Wiwynn 
H/W R&D Dept. II 
8F,90,Sec. 1,Hsin Tai Wu Rd, 
Hsichih, Taipei Hsien 221, Taiwan, R.O.C 
Q48 
PMBS3904-1-GP 
Q48 
PMBS3904-1-GP 3
1
2
C330 
SC1U16V3KX-5GP 
C330 
SC1U16V3KX-5GP 
1 2
C327 SCD01U50V2KX-1GP C327 SCD01U50V2KX-1GP 1 2
R306 
4K7R2J-2-GP 
R306 
4K7R2J-2-GP 
1 2
R405 
10KR2F-2-GP 
R405 
10KR2F-2-GP 
1 2
C331 
SC10U16V6KX-2GP 
C331 
SC10U16V6KX-2GP 
1 2 R309 
0R2J-2-GP 
R309 
0R2J-2-GP 
1 2
LED15 
LED-RB-4-GP 
LED15 
LED-RB-4-GP 
1
3 2
4
C336 
SC10U25V6KX-1GP 
C336 
SC10U25V6KX-1GP 
1 2
C328 SCD01U50V2KX-1GP C328 SCD01U50V2KX-1GP 1 2
R541 
0R1206-PAD-1-GP 
R541 
0R1206-PAD-1-GP 
1 2
C335 
SC10U25V6KX-1GP 
C335 
SC10U25V6KX-1GP 
1 2
R404 
0R2J-2-GP 
R404 
0R2J-2-GP 
1 2
S
S
S
G D
D
D
D
Q29 
AO4406AL-GP 
S
S
S
G D
D
D
D
Q29 
AO4406AL-GP 
1
2
3
4 5
6
7
8
R308 
0R2J-2-GP 
R308 
0R2J-2-GP 
1 2
F29 
POLYSW-2A6V-4-GP 
DY F29 
POLYSW-2A6V-4-GP 
DY 1 2
SKT15 
SKT-SATA14P-15P-12-GP 
SKT15 
SKT-SATA14P-15P-12-GP 
S1 
S2 
S3 
S4 
S5 
S6 
S7 
S8 
S9 
S10 
S11 
S12 
S13 
S14 
P1 
P2 
P3 
P4 
P5 
P6 
P7 
P8 
P9 
P10 
P11 
P12 
P13 
P14 
NP2 
NP1 
P15 
H2 
H1 
F30 
FUSE-3A15V-GP 
DY F30 
FUSE-3A15V-GP 
DY 12R304 
2R2010J-1-GP 
R304 
2R2010J-1-GP 
1 2
Q30 
2N7002DW-7F-GP 
Q30 
2N7002DW-7F-GP 
1
2
3 4
5
6
R474 
4K7R2J-2-GP 
R474 
4K7R2J-2-GP 
1 2
C339 
SCD1U10V2KX-5GP 
C339 
SCD1U10V2KX-5GP 
1 2
C332 
SCD01U50V2KX-1GP 
C332 
SCD01U50V2KX-1GP 
1 2
U43 
74LVC1G08GW-1-GP 
U43 
74LVC1G08GW-1-GP 
B 1
A 2
GND 3Y4
VCC 5
R477 
4K7R2J-2-GP 
R477 
4K7R2J-2-GP 
1 2
C338 
SC1U25V3KX-1-GP 
C338 
SC1U25V3KX-1-GP 
1 2
R302 
2R2010J-1-GP 
R302 
2R2010J-1-GP 
1 2
R298 
0R2J-2-GP 
R298 
0R2J-2-GP 
1 2
R307 
4K7R2J-2-GP 
R307 
4K7R2J-2-GP 
1 2
C324 
SCD1U10V2KX-5GP 
C324 
SCD1U10V2KX-5GP 
1 2
R299 
330R2F-GP 
R299 
330R2F-GP 
1 2
C326 SCD01U50V2KX-1GP C326 SCD01U50V2KX-1GP 1 2
R305 
1KR2F-3-GP 
DY R305 
1KR2F-3-GP 
DY 
1 2
S
S
S
G D
D
D
D
U44 
P2003EVG-GP 
S
S
S
G D
D
D
D
U44 
P2003EVG-GP 
1
2
3
4 5
6
7
8
C334 
SC10U25V6KX-1GP 
C334 
SC10U25V6KX-1GP 
1 2
Q75 
2N7002-11-GP 
Q75 
2N7002-11-GP 
G
SD
U45 
74LVC1G08GW-1-GP 
U45 
74LVC1G08GW-1-GP 
B1
A2
GND 3 Y 4
VCC 5
R480 
0R2J-2-GP 
R480 
0R2J-2-GP 
1 2
C333 
SC10U25V6KX-1GP 
C333 
SC10U25V6KX-1GP 
1 2
Q74 
2N7002DW-7F-GP 
Q74 
2N7002DW-7F-GP 
1
2
34
5
6
R296 
10KR2F-2-GP 
R296 
10KR2F-2-GP 
1 2
R301 
4K7R2J-2-GP 
R301 
4K7R2J-2-GP 
1 2
R303 
220R3F-1-GP 
R303 
220R3F-1-GP 
1 2
R540 
0R0805-PAD-2-GP 
R540 
0R0805-PAD-2-GP 
1 2
R476 
4K7R2J-2-GP 
R476 
4K7R2J-2-GP 
1 2
R504 
1KR2F-3-GP 
R504 
1KR2F-3-GP 
1 2
R475 
4K7R2J-2-GP 
R475 
4K7R2J-2-GP 
1 2
R300 
0R2J-2-GP 
R300 
0R2J-2-GP 
1 2
C329 SCD01U50V2KX-1GP C329 SCD01U50V2KX-1GP 1 2
R297 
402R2F-GP 
R297 
402R2F-GP 
1 2
TP39TPAD32-GP TP39TPAD32-GP 1



5
5
4
4
3
3
2
2
1
1
D D
C C
B B
A A
EEPROM 
I2C_B_TMP1 0X98 I2C_B_TMP2 0X92 
I2C_B_TMP3 0X94 
I2C_B_TMP4 0X96 
ADDR=1010001 (0XA2) 
Input Cap: 3pF 
Input Cap: 3pF 
Input Cap: 3pF 
Input Cap: 3pF 
Input Cap: 10pF 
Operating current: 5mA 
Operating current: 100 uA 
Operating current: 100 uA 
Operating current: 100 uA 
Operating current: 100 uA 
ADDR=1001000 (0x90) 
VOLTAGE SENSOR 
Operating current: 300uA 
EVT-2 
20120425 
DVT 
20120708 
DVT 
20120724 
I2C_B_TMP1_A0 
I2C_B_TMP1_A1 
I2C_B_TMP1_A2 
I2C_B_TMP2_A0 
I2C_B_TMP2_A1 
I2C_B_TMP2_A2 
I2C_B_TMP3_A0 
I2C_B_TMP3_A1 
I2C_B_TMP3_A2 
I2C_B_TMP4_A0 
I2C_B_TMP4_A1 
I2C_B_TMP4_A2 
I2C_B_TMP1_ALERT 
I2C_B_TMP2_ALERT 
EEPROM_A0 
EEPROM_A1 
EEPROM_A2 
EEPROM_WP 
I2C_B_TMP3_ALERT 
I2C_B_TMP4_ALERT 
EEPROM_SCL 
EEPROM_SDA 
TMP1_SCL 
TMP1_SDA 
TMP2_SDA 
TMP2_SCL 
TMP3_SCL 
TMP3_SDA 
TMP4_SCL 
TMP4_SDA 
P5VA_SENSE 
P5VB_SENSE 
VOL_SEN_ADDR 
VOL_SEN_ALERT 
VOL_SEN_SCL 
VOL_SEN_SDA 
P5VC_SENSE 
P12V_SENSE 
P5VA_DIV P12V_DIV P5VB_DIV P5VC_DIV 
P3V3 P3V3 
P3V3 P3V3 
P3V3 P3V3 
P3V3 P3V3 
P3V3 
P3V3 
P3V3 
P5VA_DIV P5VB_DIV P12V_DIV 
P3V3 
P3V3 
P5VA P12V P5VC_DIV P5VB P5VC 
I2C_B_SDA 12,15 
I2C_B_SCL 12,15 
I2C_B_SDA 12,15 
I2C_B_SCL 12,15 
I2C_B_SDA 12,15 
I2C_B_SCL 12,15 
I2C_B_SDA 12,15 
I2C_B_SCL 12,15 
I2C_B_SCL 12,15 
I2C_B_SDA 12,15 
I2C_B_SDA 12,15 
I2C_B_SCL 12,15 
Title 
Size Document Number Rev 
Date: Sheet 
of 
KNOX_DPB -1 
I2C B_DEVICES 
C
11 21 Thursday, October 11, 2012 
Wiwynn 
H/W R&D Dept. II 
8F,90,Sec. 1,Hsin Tai Wu Rd, 
Hsichih, Taipei Hsien 221, Taiwan, R.O.C 
Title 
Size Document Number Rev 
Date: Sheet 
of 
KNOX_DPB -1 
I2C B_DEVICES 
C
11 21 Thursday, October 11, 2012 
Wiwynn 
H/W R&D Dept. II 
8F,90,Sec. 1,Hsin Tai Wu Rd, 
Hsichih, Taipei Hsien 221, Taiwan, R.O.C 
Title 
Size Document Number Rev 
Date: Sheet 
of 
KNOX_DPB -1 
I2C B_DEVICES 
C
11 21 Thursday, October 11, 2012 
Wiwynn 
H/W R&D Dept. II 
8F,90,Sec. 1,Hsin Tai Wu Rd, 
Hsichih, Taipei Hsien 221, Taiwan, R.O.C 
R387 
10KR2F-2-GP 
R387 
10KR2F-2-GP 
1 2
R345 
4K7R2J-2-GP 
R345 
4K7R2J-2-GP 
1 2
C347 
SCD1U50V3KX-GP 
C347 
SCD1U50V3KX-GP 
1 2
U49 
TMP75AIDGKT-GP 
U49 
TMP75AIDGKT-GP 
SDA 1
SCL 2
ALERT 3
GND 4 A2 5A1 6A0 7V+ 8
R321 
4K7R2J-2-GP 
R321 
4K7R2J-2-GP 
1 2
R316 
4K7R2J-2-GP 
DY 
R316 
4K7R2J-2-GP 
DY 
1 2
R379 0R2J-2-GP R379 0R2J-2-GP 1 2
TP150 
TPAD32-GP 
TP150 
TPAD32-GP 
1
R364 
4K7R2J-2-GP 
DY R364 
4K7R2J-2-GP 
DY 
1 2
C341 
SCD1U10V2KX-5GP 
C341 
SCD1U10V2KX-5GP 
1 2
R311 
4K7R2J-2-GP 
R311 
4K7R2J-2-GP 
1 2
R482 
10KR2F-2-GP 
R482 
10KR2F-2-GP 
1 2
R320 
4K7R2J-2-GP 
DY R320 
4K7R2J-2-GP 
DY 
1 2
C353 
SCD1U16V2KX-3GP 
C353 
SCD1U16V2KX-3GP 
1 2
R315 
4K7R2J-2-GP 
DY 
R315 
4K7R2J-2-GP 
DY 
1 2
R319 
0R2J-2-GP 
R319 
0R2J-2-GP 
1 2
C346 
SC1U16V3KX-5GP 
C346 
SC1U16V3KX-5GP 
1 2
U48 
TMP75AIDGKT-GP 
U48 
TMP75AIDGKT-GP 
SDA 1
SCL 2
ALERT 3
GND 4 A2 5A1 6A0 7V+ 8
R347 
4K7R2J-2-GP DY R347 
4K7R2J-2-GP DY 1 2
R333 
4K7R2J-2-GP 
R333 
4K7R2J-2-GP 
1 2
C362 
SCD1U16V2KX-3GP 
C362 
SCD1U16V2KX-3GP 
1 2
R313 
4K7R2J-2-GP 
DY R313 
4K7R2J-2-GP 
DY 
1 2
R361 
0R2J-2-GP 
R361 
0R2J-2-GP 
1 2
R354 0R2J-2-GP R354 0R2J-2-GP 1 2
R336 
4K7R2J-2-GP 
R336 
4K7R2J-2-GP 
1 2
R325 
4K7R2J-2-GP 
DY 
R325 
4K7R2J-2-GP 
DY 1 2
R328 
4K7R2J-2-GP 
DY 
R328 
4K7R2J-2-GP 
DY 
1 2
R352 0R2J-2-GP R352 0R2J-2-GP 1 2
R484 
10KR2F-2-GP 
R484 
10KR2F-2-GP 
1 2
U53 
ADS1015IDGSR-GP 
U53 
ADS1015IDGSR-GP 
ADDR 1
ALERT/RDY 2
GND 3
AIN0 4
AIN1 5
AIN2 6
AIN3 7
VDD 8
SDA 9SCL 10 
R382 0R2J-2-GP R382 0R2J-2-GP 1 2
R326 
0R2J-2-GP 
R326 
0R2J-2-GP 
1 2
U47 
TMP75AIDGKT-GP 
U47 
TMP75AIDGKT-GP 
SDA 1
SCL 2
ALERT 3
GND 4 A2 5A1 6A0 7V+ 8
R362 
4K7R2F-GP 
DY R362 
4K7R2F-GP 
DY 
1 2
R346 
4K7R2J-2-GP 
DY 
R346 
4K7R2J-2-GP 
DY 
1 2
R339 
4K7R2J-2-GP 
R339 
4K7R2J-2-GP 
1 2
R388 
10KR2F-2-GP 
R388 
10KR2F-2-GP 
1 2
R330 
0R2J-2-GP 
R330 
0R2J-2-GP 
1 2
R389 
2KR2F-3-GP 
R389 
2KR2F-3-GP 
1 2
TP4 
TPAD32-GP 
TP4 
TPAD32-GP 
1
R337 
4K7R2J-2-GP 
DY 
R337 
4K7R2J-2-GP 
DY 
1 2
R318 
0R2J-2-GP 
R318 
0R2J-2-GP 
1 2
R324 
4K7R2J-2-GP 
R324 
4K7R2J-2-GP 
1 2
U50 
24LC64T-I-GP 
U50 
24LC64T-I-GP 
A1 2
A2 3
A0 1
SDA 5VSS 4 SCL 6WP 7VCC 8
C340 
SCD1U10V2KX-5GP 
C340 
SCD1U10V2KX-5GP 
1 2
R329 
4K7R2J-2-GP 
R329 
4K7R2J-2-GP 
1 2
C361 
SCD1U16V2KX-3GP 
C361 
SCD1U16V2KX-3GP 
1 2
R483 
10KR2F-2-GP 
R483 
10KR2F-2-GP 
1 2
C343 
SCD1U10V2KX-5GP 
C343 
SCD1U10V2KX-5GP 
1 2
R323 
4K7R2J-2-GP 
R323 
4K7R2J-2-GP 
1 2
R390 
10KR2F-2-GP 
R390 
10KR2F-2-GP 
1 2
R373 
0R2J-2-GP 
R373 
0R2J-2-GP 
1 2
R312 
4K7R2J-2-GP 
DY R312 
4K7R2J-2-GP 
DY 
1 2
R350 
4K7R2J-2-GP 
R350 
4K7R2J-2-GP 
1 2
R380 
0R2J-2-GP 
R380 
0R2J-2-GP 
1 2
R314 
0R2J-2-GP 
R314 
0R2J-2-GP 
1 2
R332 
4K7R2J-2-GP 
R332 
4K7R2J-2-GP 
1 2
R327 
4K7R2J-2-GP 
DY 
R327 
4K7R2J-2-GP 
DY 1 2
R351 0R2J-2-GP R351 0R2J-2-GP 1 2
R322 
4K7R2J-2-GP 
R322 
4K7R2J-2-GP 
1 2
C363 
SC1U10V2KX-1GP 
C363 
SC1U10V2KX-1GP 
1 2
C352 
SCD1U16V2KX-3GP 
C352 
SCD1U16V2KX-3GP 
1 2
R338 
4K7R2J-2-GP 
R338 
4K7R2J-2-GP 
1 2
R341 
4K7R2J-2-GP 
DY 
R341 
4K7R2J-2-GP 
DY 
1 2
R485 
10KR2F-2-GP 
R485 
10KR2F-2-GP 
1 2
R310 
0R2J-2-GP 
R310 
0R2J-2-GP 
1 2
R348 
4K7R2J-2-GP 
DY R348 
4K7R2J-2-GP 
DY 
1 2
C354 
SCD1U16V2KX-3GP 
C354 
SCD1U16V2KX-3GP 
1 2
C342 
SCD1U10V2KX-5GP 
C342 
SCD1U10V2KX-5GP 
1 2
U46 
TMP75AIDGKT-GP 
U46 
TMP75AIDGKT-GP 
SDA 1
SCL 2
ALERT 3
GND 4 A2 5A1 6A0 7V+ 8
R381 
4K7R2J-2-GP 
R381 
4K7R2J-2-GP 
1 2
R334 
0R2J-2-GP 
R334 
0R2J-2-GP 
1 2
R317 
4K7R2J-2-GP 
R317 
4K7R2J-2-GP 
1 2
TP2 
TPAD32-GP 
TP2 
TPAD32-GP 
1
TP3 
TPAD32-GP 
TP3 
TPAD32-GP 
1
R349 
4K7R2J-2-GP 
R349 
4K7R2J-2-GP 
1 2
R386 
0R2J-2-GP 
R386 
0R2J-2-GP 
1 2
R335 
0R2J-2-GP 
R335 
0R2J-2-GP 
1 2
R340 
4K7R2J-2-GP 
DY 
R340 
4K7R2J-2-GP 
DY 
1 2
TP1 
TPAD32-GP 
TP1 
TPAD32-GP 
1
R331 
4K7R2J-2-GP 
DY 
R331 
4K7R2J-2-GP 
DY 
1 2



5
5
4
4
3
3
2
2
1
1
D D
C C
B B
A A
REDRIVER 
REDRIVER REDRIVER 
REDRIVER 
CN1_SEB_1A/2A 
EXPA/B HB  SWAP 
EXPA/B ID setting 
EXP_A:LOW EXP_B:HI 
Ihold=3A 
Itrip=6A 
Ihold=3A 
Itrip=6A 
EVT-3 
20120412 
EVT-3 
20120412 EVT-3 
20120412 
EVT-3 
20120412 
EVT-2 
20120425 
DPB H/W REV setting 
CN2_SEB_1B/2B 
SAS Interconnection 
DPB_HW_REV R406 
  LOW 
(Default) 
HIGH 
R407 
C36 C37 
C38 C39 
x1 SAS 
Interconnection 
Dummy 
Dummy 
Dummy 
Mount 
Mount 
Mount 
NO 
Yes 
DVT 
20120701 
DVT 
20120701 
DVT 
20120701 
DVT 
20120701 
DVT 
20120701 
DVT 
20120701 
DVT 
20120701 
DVT 
20120701 
DVT 
20120701 
DVT 
20120701 
DVT 
20120701 
DVT 
20120701 
DVT 
20120701 
DVT 
20120708 DVT 
20120708 DVT 
20120708 
DVT 
20120708 
DVT 
20120712 
DVT 
20120712 
DVT 
20120710 
PVT 
20121009 PVT 
20121009 
P12V_EXP_A 
SAS2x28_A_PRSNT15 
DPB_HW_REV 
SAS2x28_B_PRSNT15 
SELF_1A&2A_HB HB_EXP_B_INPUT 
HB_EXP_A_INPUT SELF_1B&2B_HB 
SELF_1A&2A_HB 
HB_EXP_A_INPUT SELF_1B&2B_HB 
HB_EXP_B_INPUT 
TEMP_SENSOR_A_ADDR0&ID 
SEB_AB_TX+ 
SEB_AB_TX- 
SEB_BA_RX- 
SEB_BA_RX+ 
I2C_B_SCL_DAMP_B 
I2C_B_SDA_DAMP_B 
TEMP_SENSOR_B_ADDR0&ID 
SEB_BA_TX+ 
SEB_BA_TX- 
SEB_AB_RX+ 
SEB_AB_RX- 
TEMP_SENSOR_A_ADDR0&ID TEMP_SENSOR_B_ADDR0&ID 
DPB_HW_REV 
DPB_HW_REV 
SEB_BA_TX+ 
SEB_BA_TX- 
SEB_AB_TX+ 
SEB_AB_TX- 
SEB_BA_RX- 
SEB_BA_RX+ 
SEB_AB_RX+ 
SEB_AB_RX- 
SAS2x28_B_HDD15_FLT 
SAS2x28_A_HDD15_FLT 
I2C_D_SDA_DAMP_B 
I2C_D_SCL_DAMP_B 
I2C_C_SDA_DAMP_B 
I2C_C_SCL_DAMP_B 
I2C_D_SDA_DAMP_A 
I2C_D_SCL_DAMP_A 
I2C_C_SDA_DAMP_A 
I2C_C_SCL_DAMP_A 
I2C_B_SDA_DAMP_A 
I2C_B_SCL_DAMP_A 
I2C_B_SCL_DAMP_A 
I2C_B_SDA_DAMP_A 
I2C_D_SDA_DAMP_A 
I2C_D_SCL_DAMP_A 
I2C_C_SDA_DAMP_A 
I2C_C_SCL_DAMP_A 
P12V_EXP_B 
I2C_B_SCL_DAMP_B 
I2C_B_SDA_DAMP_B 
I2C_C_SCL_DAMP_B 
I2C_C_SDA_DAMP_B 
I2C_D_SCL_DAMP_B 
I2C_D_SDA_DAMP_B 
P12V 
P12V 
P3V3 P3V3 
P3V3 
SAS2x28_A_HDD12_FLT 9
SAS2x28_A_HDD11_FLT 8
SAS2x28_A_HDD9_FLT 7
SAS2x28_A_HDD8_FLT 7
SAS2x28_A_HDD11_RX_- 8
SAS2x28_A_HDD11_RX_+ 8
SAS2x28_A_HDD12_RX_- 9
SAS2x28_A_HDD12_RX_+ 9
SAS2x28_A_HDD13_RX_- 9
SAS2x28_A_HDD13_RX_+ 9
SAS2x28_A_HDD14_RX_- 10 
SAS2x28_A_HDD14_RX_+ 10 
SAS2x28_A_HDD9_RX_- 7
SAS2x28_A_HDD9_RX_+ 7
SAS2x28_A_HDD8_RX_- 7
SAS2x28_A_HDD8_RX_+ 7
SAS2x28_A_HDD7_RX_- 6
SAS2x28_A_HDD7_RX_+ 6
SAS2x28_A_HDD4_RX_- 5
SAS2x28_A_HDD4_RX_+ 5
SAS2x28_A_HDD3_RX_- 4
SAS2x28_A_HDD3_RX_+ 4
SAS2x28_A_HDD6_RX_- 6
SAS2x28_A_HDD6_RX_+ 6
SAS2x28_A_HDD13_FLT 9
SAS2x28_A_HDD14_FLT 10 
SAS2x28_A_HDD11_TX_+ 8
SAS2x28_A_HDD11_TX_- 8
SAS2x28_A_HDD12_TX_+ 9
SAS2x28_A_HDD12_TX_- 9
SAS2x28_A_HDD13_TX_+ 9
SAS2x28_A_HDD13_TX_- 9
SAS2x28_A_HDD14_TX_+ 10 
SAS2x28_A_HDD14_TX_- 10 
SAS2x28_A_HDD9_TX_+ 7
SAS2x28_A_HDD7_TX_+ 6
SAS2x28_A_HDD7_TX_- 6
SAS2x28_A_HDD4_TX_+ 5
SAS2x28_A_HDD4_TX_- 5
SAS2x28_A_HDD9_TX_- 7
SAS2x28_A_HDD8_TX_+ 7
SAS2x28_A_HDD8_TX_- 7
SAS2x28_A_HDD3_TX_+ 4
SAS2x28_A_HDD3_TX_- 4
SAS2x28_A_HDD6_TX_+ 6
SAS2x28_A_HDD6_TX_- 6
SAS2x28_A_HDD0_FLT 3
SAS2x28_A_HDD10_FLT 8
SAS2x28_A_HDD1_FLT 3
SAS2x28_A_HDD2_FLT 4
SAS2x28_A_HDD6_FLT 6
PWM_EXP_A 14 
SAS2x28_B_HDD6_RX_+ 6
SAS2x28_B_HDD14_FLT 10 
SAS2x28_B_HDD8_RX_- 7
SAS2x28_B_HDD8_RX_+ 7
SAS2x28_B_HDD2_FLT 4
SAS2x28_B_HDD6_RX_- 6
SAS2x28_B_HDD8_FLT 7
SAS2x28_B_HDD7_RX_- 6
SAS2x28_B_HDD7_RX_+ 6
SAS2x28_B_HDD5_RX_+ 5
SAS2x28_B_HDD5_RX_- 5
SAS2x28_B_HDD1_RX_- 3
SAS2x28_B_HDD1_RX_+ 3
SAS2x28_B_HDD0_RX_- 3
SAS2x28_B_HDD0_RX_+ 3
SAS2x28_B_HDD10_RX_+ 8
SAS2x28_B_HDD10_RX_- 8
SAS2x28_B_HDD13_RX_- 9
SAS2x28_B_HDD13_RX_+ 9
SAS2x28_B_HDD14_RX_- 10 
SAS2x28_B_HDD9_RX_- 7
SAS2x28_B_HDD9_RX_+ 7
SAS2x28_B_HDD11_RX_+ 8
SAS2x28_B_HDD11_RX_- 8
SAS2x28_B_HDD14_RX_+ 10 
SAS2x28_B_HDD3_RX_- 4
SAS2x28_B_HDD3_RX_+ 4
SAS2x28_B_HDD9_FLT 7
SAS2x28_B_HDD2_RX_- 4
SAS2x28_B_HDD2_RX_+ 4
SAS2x28_B_HDD12_RX_+ 9
SAS2x28_B_HDD3_FLT 4
SAS2x28_B_HDD12_RX_- 9
SAS2x28_B_HDD4_RX_- 5
SAS2x28_B_HDD4_RX_+ 5
SAS2x28_B_HDD4_FLT 5
SAS2x28_B_HDD0_TX_+ 3
SAS2x28_B_HDD0_TX_- 3
SAS2x28_B_HDD13_TX_+ 9
SAS2x28_B_HDD13_TX_- 9
SAS2x28_B_HDD14_TX_+ 10 
SAS2x28_B_HDD9_TX_+ 7
SAS2x28_B_HDD9_TX_- 7
SAS2x28_B_HDD3_TX_+ 4
SAS2x28_B_HDD3_TX_- 4
SAS2x28_B_HDD6_FLT 6
SAS2x28_B_HDD11_FLT 8
SAS2x28_B_HDD10_FLT 8
SAS2x28_B_HDD5_FLT 5
SAS2x28_B_HDD14_TX_- 10 
SAS2x28_B_HDD2_TX_+ 4
SAS2x28_B_HDD7_TX_+ 6
SAS2x28_B_HDD7_TX_- 6
SAS2x28_B_HDD1_TX_+ 3
SAS2x28_B_HDD1_TX_- 3
SAS2x28_B_HDD2_TX_- 4
SAS2x28_B_HDD8_TX_+ 7
SAS2x28_B_HDD8_TX_- 7
SAS2x28_B_HDD13_FLT 9
SAS2x28_B_HDD4_TX_+ 5
SAS2x28_B_HDD4_TX_- 5
SAS2x28_A_HDD7_FLT 6
SAS2x28_B_HDD7_FLT 6
SAS2x28_A_HDD5_FLT 5
SAS2x28_A_HDD4_FLT 5
SAS2x28_A_HDD3_FLT 4
SAS2x28_B_HDD12_FLT 9
PWM_EXP_B 14 
SAS2x28_B_HDD1_FLT 3
SAS2x28_B_HDD0_FLT 3
SAS2x28_A_HDD2_RX_+ 4
SAS2x28_A_HDD2_RX_- 4
SAS2x28_A_HDD1_RX_+ 3
SAS2x28_A_HDD1_RX_- 3
SAS2x28_A_HDD10_RX_+ 8
SAS2x28_A_HDD10_RX_- 8
SAS2x28_A_HDD0_RX_+ 3
SAS2x28_A_HDD0_RX_- 3
SAS2x28_A_HDD5_RX_+ 5
SAS2x28_A_HDD5_RX_- 5
SAS2x28_A_HDD2_TX_+ 4
SAS2x28_A_HDD2_TX_- 4
SAS2x28_A_HDD1_TX_+ 3
SAS2x28_A_HDD1_TX_- 3
SAS2x28_A_HDD10_TX_+ 8
SAS2x28_A_HDD10_TX_- 8
SAS2x28_A_HDD0_TX_+ 3
SAS2x28_A_HDD0_TX_- 3
SAS2x28_A_HDD5_TX_+ 5
SAS2x28_A_HDD5_TX_- 5
SAS2x28_B_HDD6_TX_+ 6
SAS2x28_B_HDD6_TX_- 6
SAS2x28_B_HDD5_TX_+ 5
SAS2x28_B_HDD5_TX_- 5
SAS2x28_B_HDD10_TX_+ 8
SAS2x28_B_HDD10_TX_- 8
SAS2x28_B_HDD11_TX_+ 8
SAS2x28_B_HDD11_TX_- 8
SAS2x28_B_HDD12_TX_+ 9
SAS2x28_B_HDD12_TX_- 9
FCB_HW_REV 14 
FCB_HW_REV 14 
TRAY_ID 14 
TRAY_ID 14 
PEER_1A&2A_HB 14 
PEER_1A&2A_HB 14 
PEER_1B&2B_HB 14 
SELF_1B&2B_HB 14 
SELF_1A&2A_HB 14 
I2C_D_SDA 15 
I2C_D_SCL 15 
I2C_C_SDA 14 
I2C_C_SCL 14 
I2C_B_SCL 11,15 
I2C_B_SDA 11,15 
SD_LATCH_RELEASE 12 
SD_LATCH_RELEASE 12 
PEER_1B&2B_HB 14 
Title 
Size Document Number Rev 
Date: Sheet 
of 
KNOX_DPB -1 
PCIE SLOTS x16 
C
12 21 Thursday, October 11, 2012 
Wiwynn 
H/W R&D Dept. II 
8F,90,Sec. 1,Hsin Tai Wu Rd, 
Hsichih, Taipei Hsien 221, Taiwan, R.O.C 
Title 
Size Document Number Rev 
Date: Sheet 
of 
KNOX_DPB -1 
PCIE SLOTS x16 
C
12 21 Thursday, October 11, 2012 
Wiwynn 
H/W R&D Dept. II 
8F,90,Sec. 1,Hsin Tai Wu Rd, 
Hsichih, Taipei Hsien 221, Taiwan, R.O.C 
Title 
Size Document Number Rev 
Date: Sheet 
of 
KNOX_DPB -1 
PCIE SLOTS x16 
C
12 21 Thursday, October 11, 2012 
Wiwynn 
H/W R&D Dept. II 
8F,90,Sec. 1,Hsin Tai Wu Rd, 
Hsichih, Taipei Hsien 221, Taiwan, R.O.C 
F32 
FUSE-3A15V-GP 
DY F32 
FUSE-3A15V-GP 
DY 
1 2
TP15 TPAD32-GP TP15 TPAD32-GP 
1
R542 
0R1206-PAD-1-GP 
R542 
0R1206-PAD-1-GP 
1 2
R546 0R2J-2-GP R546 0R2J-2-GP 1 2
R481 0R2J-2-GP R481 0R2J-2-GP 1 2
R508 0R2J-2-GP R508 0R2J-2-GP 1 2
R545 0R2J-2-GP R545 0R2J-2-GP 1 2
R407 
100R2J-2-GP 
R407 
100R2J-2-GP 
1 2
R549 0R2J-2-GP R549 0R2J-2-GP 1 2
R511 0R2J-2-GP R511 0R2J-2-GP 1 2
TP6 
TPAD32-GP 
TP6 
TPAD32-GP 1
TOP BOTTOM 
02 Do not mirror 
CN1 
PCISLT164-70-GP 
TOP BOTTOM 
02 Do not mirror 
CN1 
PCISLT164-70-GP 
B1 
B2 
B3 
B4 
B5 
B6 
B7 
B8 
B9 
B10 
B11 
B12 
B13 
B14 
B15 
B16 
B17 
B18 
B19 
B20 
B21 
B22 
B23 
B24 
B25 
B26 
B27 
B28 
B29 
B30 
B31 
B32 
B33 
B34 
B35 
B36 
B37 
B38 
B39 
B40 
B41 
B42 
B43 
B44 
B45 
B46 
B47 
B48 
B49 
B50 
B51 
B52 
B53 
B54 
B55 
B56 
B57 
B58 
B59 
B60 
B61 
B62 
B63 
B64 
B65 
B66 
B67 
B68 
B69 
B70 
B71 
B72 
B73 
B74 
B75 
B76 
B77 
B78 
B79 
B80 
B81 
B82 
A1 
A2 
A3 
A4 
A5 
A6 
A7 
A8 
A9 
A10 
A11 
A12 
A13 
A14 
A15 
A16 
A17 
A18 
A19 
A20 
A21 
A22 
A23 
A24 
A25 
A26 
A27 
A28 
A29 
A30 
A31 
A32 
A33 
A34 
A35 
A36 
A37 
A38 
A39 
A40 
A41 
A42 
A43 
A44 
A45 
A46 
A47 
A48 
A49 
A50 
A51 
A52 
A53 
A54 
A55 
A56 
A57 
A58 
A59 
A60 
A61 
A62 
A63 
A64 
A65 
A66 
A67 
A68 
A69 
A70 
A71 
A72 
A73 
A74 
A75 
A76 
A77 
A78 
A79 
A80 
A81 
A82 
NP1 
NP2 
TP5 
TPAD32-GP 
TP5 
TPAD32-GP 1
R406 
10KR2F-2-GP 
DY R406 
10KR2F-2-GP 
DY 
1 2
R355 
10KR2F-2-GP 
DY R355 
10KR2F-2-GP 
DY 
1 2
R548 0R2J-2-GP R548 0R2J-2-GP 1 2
C351 
SC10U25V5KX-GP 
C351 
SC10U25V5KX-GP 
1 2
R360 
0R2J-2-GP 
R360 
0R2J-2-GP 
1 2R359 
10KR2F-2-GP 
DY R359 
10KR2F-2-GP 
DY 
1 2
R544 0R2J-2-GP R544 0R2J-2-GP 1 2
C39 SCD01U50V2KX-1GP 
DY 
C39 SCD01U50V2KX-1GP 
DY 
1 2
R357 
0R2J-2-GP 
R357 
0R2J-2-GP 
1 2
R358 
100R2J-2-GP 
R358 
100R2J-2-GP 
1 2
TP12 TPAD32-GP TP12 TPAD32-GP 
1
C38 SCD01U50V2KX-1GP 
DY 
C38 SCD01U50V2KX-1GP 
DY 
1 2
R356 
10KR2F-2-GP 
R356 
10KR2F-2-GP 
1 2
R547 0R2J-2-GP R547 0R2J-2-GP 1 2
R509 0R2J-2-GP R509 0R2J-2-GP 1 2
R510 0R2J-2-GP R510 0R2J-2-GP 1 2
TC2 
ST15U25VDM-1-GP 
TC2 
ST15U25VDM-1-GP 
1 2
TC1 
ST15U25VDM-1-GP 
TC1 
ST15U25VDM-1-GP 
1 2
TOP BOTTOM 
02 Do not mirror 
CN2 
PCISLT164-70-GP 
TOP BOTTOM 
02 Do not mirror 
CN2 
PCISLT164-70-GP 
B1 
B2 
B3 
B4 
B5 
B6 
B7 
B8 
B9 
B10 
B11 
B12 
B13 
B14 
B15 
B16 
B17 
B18 
B19 
B20 
B21 
B22 
B23 
B24 
B25 
B26 
B27 
B28 
B29 
B30 
B31 
B32 
B33 
B34 
B35 
B36 
B37 
B38 
B39 
B40 
B41 
B42 
B43 
B44 
B45 
B46 
B47 
B48 
B49 
B50 
B51 
B52 
B53 
B54 
B55 
B56 
B57 
B58 
B59 
B60 
B61 
B62 
B63 
B64 
B65 
B66 
B67 
B68 
B69 
B70 
B71 
B72 
B73 
B74 
B75 
B76 
B77 
B78 
B79 
B80 
B81 
B82 
A1 
A2 
A3 
A4 
A5 
A6 
A7 
A8 
A9 
A10 
A11 
A12 
A13 
A14 
A15 
A16 
A17 
A18 
A19 
A20 
A21 
A22 
A23 
A24 
A25 
A26 
A27 
A28 
A29 
A30 
A31 
A32 
A33 
A34 
A35 
A36 
A37 
A38 
A39 
A40 
A41 
A42 
A43 
A44 
A45 
A46 
A47 
A48 
A49 
A50 
A51 
A52 
A53 
A54 
A55 
A56 
A57 
A58 
A59 
A60 
A61 
A62 
A63 
A64 
A65 
A66 
A67 
A68 
A69 
A70 
A71 
A72 
A73 
A74 
A75 
A76 
A77 
A78 
A79 
A80 
A81 
A82 
NP1 
NP2 
C37 SCD01U50V2KX-1GP 
DY 
C37 SCD01U50V2KX-1GP 
DY 
1 2
R507 0R2J-2-GP R507 0R2J-2-GP 1 2
F31 
FUSE-3A15V-GP 
DY F31 
FUSE-3A15V-GP 
DY 
1 2
C36 SCD01U50V2KX-1GP 
DY 
C36 SCD01U50V2KX-1GP 
DY 
1 2
C350 
SC10U25V5KX-GP 
C350 
SC10U25V5KX-GP 
1 2
R543 
0R1206-PAD-1-GP 
R543 
0R1206-PAD-1-GP 
1 2



5
5
4
4
3
3
2
2
1
1
D D
C C
B B
A A
EXP_A_36P PCIE CONN EXP_B_36P PCIE CONN 
HDD_PRSNT MAP TO EXP_36P PCIE CONN 
modify to map HDD PWR signals 
2012.04.12 
EVT-3 
20120412 
EVT-3 
20120412 
EVT-3 
20120412 
DVT 
20120630 DVT 
20120630 
HDD_EXP_A_PRSNT0 
SAS_EXP_B_PWR15 
SAS_EXP_A_PWR15 
HDD_EXP_B_PRSNT0 
EXP_B_PRNST_RX 
EXP_A_PRNST_TX 
EXP_B_PRNST_TX 
EXP_A_PRNST_RX 
HDD_PRSNT0 
HDD_EXP_A_PRSNT13 
HDD_EXP_B_PRSNT8 
HDD_PRSNT1 
HDD_EXP_A_PRSNT11 
HDD_EXP_B_PRSNT7 
HDD_PRSNT3 
HDD_EXP_A_PRSNT8 
HDD_EXP_B_PRSNT3 
HDD_PRSNT2 
HDD_EXP_A_PRSNT10 
HDD_EXP_B_PRSNT4 
HDD_PRSNT5 
HDD_EXP_A_PRSNT14 
HDD_EXP_B_PRSNT11 
HDD_PRSNT4 
HDD_PRSNT7 
HDD_EXP_A_PRSNT6 
HDD_EXP_B_PRSNT6 
HDD_PRSN6 
HDD_EXP_A_PRSNT9 
HDD_EXP_B_PRSNT10 
HDD_EXP_A_PRSNT7 
HDD_EXP_B_PRSNT1 
HDD_EXP_A_PRSNT1 
HDD_EXP_A_PRSNT2 
HDD_EXP_A_PRSNT3 
HDD_EXP_A_PRSNT4 
HDD_EXP_A_PRSNT5 
HDD_EXP_A_PRSNT6 
HDD_EXP_A_PRSNT7 
HDD_EXP_A_PRSNT8 
HDD_EXP_A_PRSNT9 
HDD_EXP_A_PRSNT10 
HDD_EXP_A_PRSNT11 
HDD_EXP_A_PRSNT12 
HDD_EXP_A_PRSNT13 
HDD_EXP_A_PRSNT14 
HDD_EXP_B_PRSNT1 
HDD_EXP_B_PRSNT2 
HDD_EXP_B_PRSNT3 
HDD_EXP_B_PRSNT4 
HDD_EXP_B_PRSNT5 
HDD_EXP_B_PRSNT6 
HDD_EXP_B_PRSNT7 
HDD_EXP_B_PRSNT8 
HDD_EXP_B_PRSNT9 
HDD_EXP_B_PRSNT10 
HDD_EXP_B_PRSNT11 
HDD_EXP_B_PRSNT12 
HDD_EXP_B_PRSNT13 
HDD_EXP_B_PRSNT14 
HDD_PRSNT8 
HDD_EXP_A_PRSNT5 
HDD_EXP_B_PRSNT5 
HDD_PRSNT10 
HDD_EXP_A_PRSNT12 
HDD_EXP_B_PRSNT12 
HDD_PRSNT9 
HDD_EXP_A_PRSNT4 
HDD_EXP_B_PRSNT2 
HDD_PRSNT12 
HDD_EXP_A_PRSNT1 
HDD_EXP_B_PRSNT14 
HDD_PRSNT11 
HDD_PRSNT14 
HDD_EXP_A_PRSNT3 
HDD_EXP_B_PRSNT0 
HDD_PRSN13 
HDD_EXP_A_PRSNT2 
HDD_EXP_B_PRSNT9 
HDD_EXP_A_PRSNT0 
HDD_EXP_B_PRSNT13 
SAS_EXP_A_PWR11 8
SAS_EXP_A_PWR12 9
SAS_EXP_A_PWR13 9
SAS_EXP_A_PWR14 10 
SAS_EXP_A_PWR9 7
SAS_EXP_A_PWR8 7
SAS_EXP_A_PWR7 6
SAS_EXP_A_PWR4 5
SAS_EXP_A_PWR3 4
SAS_EXP_A_PWR6 6
SAS_EXP_A_PWR2 4
SAS_EXP_A_PWR1 3
SAS_EXP_A_PWR10 8
SAS_EXP_A_PWR0 3
SAS_EXP_A_PWR5 5
SAS_EXP_B_PWR12 9
SAS_EXP_B_PWR14 10 
SAS_EXP_B_PWR4 5
SAS_EXP_B_PWR9 7
SAS_EXP_B_PWR3 4
SAS_EXP_B_PWR2 4
SAS_EXP_B_PWR8 7
SAS_EXP_B_PWR7 6
SAS_EXP_B_PWR1 3
SAS_EXP_B_PWR0 3
SAS_EXP_B_PWR13 9
SAS_EXP_B_PWR6 6
SAS_EXP_B_PWR5 5
SAS_EXP_B_PWR10 8
SAS_EXP_B_PWR11 8
HDD_PRSNT0 3
HDD_PRSNT1 3
HDD_PRSNT2 4
HDD_PRSNT3 4
HDD_PRSNT4 5
HDD_PRSNT5 5
HDD_PRSNT6 6
HDD_PRSNT7 6
HDD_PRSNT8 7
HDD_PRSNT9 7
HDD_PRSNT10 8
HDD_PRSNT11 8
HDD_PRSNT12 9
HDD_PRSNT13 9
HDD_PRSNT14 10 
EXP_B_PRNST_TX 14 
EXP_A_PRNST_TX 14 
PEER_TRAY_PRESENT 14 
SELF_TRAY_PRESENT 14 
PEER_TRAY_PRESENT 14 
SELF_TRAY_PRESENT 14 
Title 
Size Document Number Rev 
Date: Sheet 
of 
KNOX_DPB -1 
PCIE SLOTS x1 
A3 
13 21 Thursday, October 11, 2012 
Wiwynn 
H/W R&D Dept. II 
8F,90,Sec. 1,Hsin Tai Wu Rd, 
Hsichih, Taipei Hsien 221, Taiwan, R.O.C 
Title 
Size Document Number Rev 
Date: Sheet 
of 
KNOX_DPB -1 
PCIE SLOTS x1 
A3 
13 21 Thursday, October 11, 2012 
Wiwynn 
H/W R&D Dept. II 
8F,90,Sec. 1,Hsin Tai Wu Rd, 
Hsichih, Taipei Hsien 221, Taiwan, R.O.C 
Title 
Size Document Number Rev 
Date: Sheet 
of 
KNOX_DPB -1 
PCIE SLOTS x1 
A3 
13 21 Thursday, October 11, 2012 
Wiwynn 
H/W R&D Dept. II 
8F,90,Sec. 1,Hsin Tai Wu Rd, 
Hsichih, Taipei Hsien 221, Taiwan, R.O.C 
TP18 
TPAD32-GP 
TP18 
TPAD32-GP 
1
R391 0R2J-2-GP R391 0R2J-2-GP 1 2
R392 0R2J-2-GP R392 0R2J-2-GP 1 2
TOP BOTTOM 
02 Do not mirror 
CN6 
PCISLT36-27-GP 
TOP BOTTOM 
02 Do not mirror 
CN6 
PCISLT36-27-GP 
NP1 NP1 NP2 NP2 
B1 B1 
B2 B2 
B3 B3 
B4 B4 
B5 B5 
B6 B6 
B7 B7 
B8 B8 
B9 B9 
B10 B10 
B11 B11 
B12 B12 
B13 B13 
B14 B14 
B15 B15 
B16 B16 
B17 B17 
B18 B18 
A1 A1 
A2 A2 
A3 A3 
A4 A4 
A5 A5 
A6 A6 
A7 A7 
A8 A8 
A9 A9 
A10 A10 
A11 A11 
A12 A12 
A13 A13 
A14 A14 
A15 A15 
A16 A16 
A17 A17 
A18 A18 
TOP BOTTOM 
02 Do not mirror 
CN5 
PCISLT36-27-GP 
TOP BOTTOM 
02 Do not mirror 
CN5 
PCISLT36-27-GP 
NP1 NP1 NP2 NP2 
B1 B1 
B2 B2 
B3 B3 
B4 B4 
B5 B5 
B6 B6 
B7 B7 
B8 B8 
B9 B9 
B10 B10 
B11 B11 
B12 B12 
B13 B13 
B14 B14 
B15 B15 
B16 B16 
B17 B17 
B18 B18 
A1 A1 
A2 A2 
A3 A3 
A4 A4 
A5 A5 
A6 A6 
A7 A7 
A8 A8 
A9 A9 
A10 A10 
A11 A11 
A12 A12 
A13 A13 
A14 A14 
A15 A15 
A16 A16 
A17 A17 
A18 A18 
TP17 
TPAD32-GP 
TP17 
TPAD32-GP 
1



5
5
4
4
3
3
2
2
1
1
D D
C C
B B
A A
DVT 
20120630 
DVT 
20120705 
STRADDLE CONN 
DVT 
20120710 
P12V 
P12V 
P3V3 
P5VA 
SELF_1A&2A_HB 12 
SELF_1B&2B_HB 12 
FCB_HW_REV 12 
TRAY_ID 12 
I2C_C_SCL 12 
I2C_C_SDA 12 
PEER_TRAY_PRESENT 12 
SELF_TRAY_PRESENT 12 
SD_LATCH_RELEASE 12 
PWM_EXP_B 12 
PWM_EXP_A 12 
PEER_1A&2A_HB 12 
PEER_1B&2B_HB 12 
Title 
Size Document Number Rev 
Date: Sheet 
of 
KNOX_DPB -1 
STRADDLE CONN 
A3 
14 21 Thursday, October 11, 2012 
Wiwynn 
H/W R&D Dept. II 
8F,90,Sec. 1,Hsin Tai Wu Rd, 
Hsichih, Taipei Hsien 221, Taiwan, R.O.C 
Title 
Size Document Number Rev 
Date: Sheet 
of 
KNOX_DPB -1 
STRADDLE CONN 
A3 
14 21 Thursday, October 11, 2012 
Wiwynn 
H/W R&D Dept. II 
8F,90,Sec. 1,Hsin Tai Wu Rd, 
Hsichih, Taipei Hsien 221, Taiwan, R.O.C 
Title 
Size Document Number Rev 
Date: Sheet 
of 
KNOX_DPB -1 
STRADDLE CONN 
A3 
14 21 Thursday, October 11, 2012 
Wiwynn 
H/W R&D Dept. II 
8F,90,Sec. 1,Hsin Tai Wu Rd, 
Hsichih, Taipei Hsien 221, Taiwan, R.O.C 
C356 
SC220P50V3JN-GP 
DY C356 
SC220P50V3JN-GP 
DY 
1 2
TOP BOTTOM 
02 Do not mirror 
CN7 
AMP-CONN60-5-GP 
TOP BOTTOM 
02 Do not mirror 
CN7 
AMP-CONN60-5-GP 
P1 
P2 
P3 
P4 
P5 
P6 
P7 
P8 
P9 
P10 
P11 
P12 
P13 
P14 
P15 
P16 
P17 
P18 P19 
P20 
P21 
P22 
P23 
P24 
P25 
P26 
P27 
P28 
P29 
P30 
P31 
P32 
P33 
P34 
P35 
P36 
S1 
S2 
S3 
S4 
S5 
S6 
S7 
S8 
S9 
S10 
S11 
S13 
S14 
S15 
S16 
S17 
S18 
S19 
S20 
S21 
S22 
S23 
S24 
NP1 
NP2 
S12 
C349 
SC10U25V6KX-1GP 
C349 
SC10U25V6KX-1GP 
1 2
C355 
SC220P50V3JN-GP 
DY C355 
SC220P50V3JN-GP 
DY 
1 2
C348 
SC10U25V6KX-1GP 
C348 
SC10U25V6KX-1GP 
1 2



5
5
4
4
3
3
2
2
1
1
D D
C C
B B
A A
 I2C_D Pull-High  I2C_B Pull-High 
VIN=12V 
VOUT=3.3V 
MAX=0.2A 
OCP=1.5A 
FS=500kHz 
P3V3 SWITCHING SY8021 
DVT 
20120626 
DVT 
20120626 
DVT 
20120626 
Between CN1 and CN2 
DVT 
20120724 
DVT 
20120724 
TOKO 22uH 
DCR=115m ohm,Irate =0.77A,Isat=1.34A 
6.3*6.2*3.0 mm3 
PVT 
20121011 PVT 
20121011 
P3V3_IN 
P3V3_BS_NET 
P3V3_LX_Cooper P3V3_LX 
P3V3_EN 
P3V3_FB_R 
P3V3_FB 
P3V3 
P3V3 
P12V 
P3V3 
I2C_D_SCL 12 
I2C_D_SDA 12 I2C_B_SDA 11,12 
I2C_B_SCL 11,12 
Title 
Size Document Number Rev 
Date: Sheet 
of 
KNOX_DPB -1 
P3V3_SY8201 
A3 
15 21 Thursday, October 11, 2012 
Wiwynn 
H/W R&D Dept. II 
8F,90,Sec. 1,Hsin Tai Wu Rd, 
Hsichih, Taipei Hsien 221, Taiwan, R.O.C 
Title 
Size Document Number Rev 
Date: Sheet 
of 
KNOX_DPB -1 
P3V3_SY8201 
A3 
15 21 Thursday, October 11, 2012 
Wiwynn 
H/W R&D Dept. II 
8F,90,Sec. 1,Hsin Tai Wu Rd, 
Hsichih, Taipei Hsien 221, Taiwan, R.O.C 
Title 
Size Document Number Rev 
Date: Sheet 
of 
KNOX_DPB -1 
P3V3_SY8201 
A3 
15 21 Thursday, October 11, 2012 
Wiwynn 
H/W R&D Dept. II 
8F,90,Sec. 1,Hsin Tai Wu Rd, 
Hsichih, Taipei Hsien 221, Taiwan, R.O.C 
PC43 
SC22U16V6MX-GP 
PC43 
SC22U16V6MX-GP 
1 2
PR57 
0R0805-PAD-2-GP 
PR57 
0R0805-PAD-2-GP 
1 2
R368 
4K7R2J-2-GP 
R368 
4K7R2J-2-GP 
1 2
PC42 
SC22P50V3JN-GP 
PC42 
SC22P50V3JN-GP 
1 2
PC41 
SCD1U16V2KX-3GP 
PC41 
SCD1U16V2KX-3GP 
1 2
R372 
4K7R2J-2-GP 
R372 
4K7R2J-2-GP 
1 2
PR53 
10KR2F-2-GP 
PR53 
10KR2F-2-GP 
1 2
PR55 
100KR2F-L1-GP 
PR55 
100KR2F-L1-GP 
1 2
PR63 
0R0603-PAD-2-GP 
PR63 
0R0603-PAD-2-GP 
1 2
PL7 
IND-22UH-169-GP 
PL7 
IND-22UH-169-GP 
1 2
U54 
SY8201ABC-GP 
U54 
SY8201ABC-GP 
BS 1 GND 2
FB 3EN 4
IN 5 LX 6
PR54 
0R3J-0-U-GP 
PR54 
0R3J-0-U-GP 
1 2
R367 
4K7R2J-2-GP 
R367 
4K7R2J-2-GP 
1 2
PR56 
22K1R3F-GP 
PR56 
22K1R3F-GP 
1 2
PC40 
SC4D7U50V6KX-L2-GP 
PC40 
SC4D7U50V6KX-L2-GP 
1 2
PR52 
47KR2J-2-GP 
PR52 
47KR2J-2-GP 
1 2
R371 
4K7R2J-2-GP 
R371 
4K7R2J-2-GP 
1 2



5
5
4
4
3
3
2
2
1
1
D D
C C
B B
A A
Vout=0.6x(1+Ru/Rd) 
=4.992V 
Vishay 4.7uH 
DCR=15m ohm,Irate =10A,Isat=24A 
13.2*12.9*3.5 mm3 
VIN=12V 
VOUT=5V 
MAX=7A 
OCP=10A 
FS=250kHz 
5V SWITCHING TPS53319 
Switching Frequency 
Adjustment 
DVT 
20120719 
DVT 
20120712 
DVT 
20120724 
P5VA_VBST_NET 
P5VA_MODE_PG 
P5VA_PGD 
P5VA_VBST 
P5VA_RF 
P5VA_VFB_NET 
P5VA_LL_NET 
P5VA_SNB 
P5VA_VFB 
P5VA_TRIP 
P5VA_12VIN 
P5VA_VDD 
P5VA_EN 
P5VA_ROVP 
P5VA_LL 
P5VA_MODE 
P5VA 
P12V 
P5VA_VREG 
P5VA_VREG 
P5VA_AGND 
P5VA 
P5VA_AGND 
P5VA_AGND 
P5VA_AGND 
Title 
Size Document Number Rev 
Date: Sheet 
of 
KNOX_DPB 1A 
P5VA FOR HDD 0-4 
A3 
16 21 Thursday, October 11, 2012 
Wiwynn 
H/W R&D Dept. II 
8F,90,Sec. 1,Hsin Tai Wu Rd, 
Hsichih, Taipei Hsien 221, Taiwan, R.O.C 
Title 
Size Document Number Rev 
Date: Sheet 
of 
KNOX_DPB 1A 
P5VA FOR HDD 0-4 
A3 
16 21 Thursday, October 11, 2012 
Wiwynn 
H/W R&D Dept. II 
8F,90,Sec. 1,Hsin Tai Wu Rd, 
Hsichih, Taipei Hsien 221, Taiwan, R.O.C 
Title 
Size Document Number Rev 
Date: Sheet 
of 
KNOX_DPB 1A 
P5VA FOR HDD 0-4 
A3 
16 21 Thursday, October 11, 2012 
Wiwynn 
H/W R&D Dept. II 
8F,90,Sec. 1,Hsin Tai Wu Rd, 
Hsichih, Taipei Hsien 221, Taiwan, R.O.C 
PR8 
3D01R2F-GP 
DY PR8 
3D01R2F-GP 
DY 
12
PC9 
SC2200P50V2KX-2GP 
DY PC9 
SC2200P50V2KX-2GP 
DY 
1 2
PC2 
SC22U25V5MX-GP 
PC2 
SC22U25V5MX-GP 
1 2
PR15 
10KR2D-GP 
PR15 
10KR2D-GP 
1 2
PC6 
SC4D7U25V5KX-GP 
PC6 
SC4D7U25V5KX-GP 
1 2
PC7 
SCD1U25V2KX-GP 
PC7 
SCD1U25V2KX-GP 
1 2
PR13 
115KR2F-GP 
PR13 
115KR2F-GP 
1 2
PC12 
SC10U16V6KX-2GP 
PC12 
SC10U16V6KX-2GP 
1 2
PR4 
0R3J-0-U-GP 
PR4 
0R3J-0-U-GP 
1 2
TP19 
TPAD32-GP 
TP19 
TPAD32-GP 
1
PC10 
SC1U10V2KX-1GP 
PC10 
SC1U10V2KX-1GP 
1 2
PR49 
10KR2F-2-GP 
PR49 
10KR2F-2-GP 
1 2
PC8 
SCD1U25V2KX-GP 
PC8 
SCD1U25V2KX-GP 
1 2
PR11 
73K2R2F-GP 
PR11 
73K2R2F-GP 
1 2
PG1 
COPPER-CLOSE-GP-U 
PG1 
COPPER-CLOSE-GP-U 
1 2
PR12 
866KR2F-GP 
DY PR12 
866KR2F-GP 
DY 
1 2
PTC1 
ST330U10VDM-2GP 
PTC1 
ST330U10VDM-2GP 
1 2
PL1 
BLM41PG600-GP 
PL1 
BLM41PG600-GP 
1 2
PR7 
0R2J-2-GP 
PR7 
0R2J-2-GP 
1 2
PC5 
SC22U25V5MX-GP 
PC5 
SC22U25V5MX-GP 
1 2
PR10 
100KR2F-L1-GP 
PR10 
100KR2F-L1-GP 
1 2
PR2 
10KR2F-2-GP 
PR2 
10KR2F-2-GP 
1 2
PC3 
SC22U25V5MX-GP 
PC3 
SC22U25V5MX-GP 
1 2
PL2 
IND-4D7UH-291-GP 
PL2 
IND-4D7UH-291-GP 
1 2
PC11 
SC10U16V6KX-2GP 
PC11 
SC10U16V6KX-2GP 
1 2
PR9 
76K8R2F-GP 
PR9 
76K8R2F-GP 
12
PR3 
2K49R2F-GP 
PR3 
2K49R2F-GP 
1 2
PR16 
0R2J-2-GP 
PR16 
0R2J-2-GP 
1 2
PR1 
0R3J-0-U-GP 
PR1 
0R3J-0-U-GP 
1 2
PR6 
10R2F-L-GP 
PR6 
10R2F-L-GP 
1 2
PC13 
SC1KP50V2KX-1GP 
PC13 
SC1KP50V2KX-1GP 
1 2
PTC2 
ST330U10VDM-2GP 
PTC2 
ST330U10VDM-2GP 
1 2
TP22 
TPAD32-GP 
TP22 
TPAD32-GP 
1
PC1 
SC22U25V5MX-GP 
PC1 
SC22U25V5MX-GP 
1 2
PR14 
10KR2D-GP 
PR14 
10KR2D-GP 
1 2
PU1 
TPS53319DQPR-GP 
PU1 
TPS53319DQPR-GP 
VFB 1PGOOD 3
EN 2
VBST 4
ROVP 5
LL#6 6
LL#7 7
LL#8 8
LL#9 9
LL#10 10 
LL#11 11 
VIN 12 VIN 13 VIN 14 VIN 15 VIN 16 VIN 17 
VREG 18 
VDD 19 
MODE 20 
TRIP 21 
RF 22 
GND 23 
PC4 
SC22U25V5MX-GP 
PC4 
SC22U25V5MX-GP 
1 2
PR5 
10KR2F-2-GP 
PR5 
10KR2F-2-GP 
1 2



5
5
4
4
3
3
2
2
1
1
D D
C C
B B
A A
Vishay 4.7uH 
DCR=15m ohm,Irate =10A,Isat=24A 
13.2*12.9*3.5 mm3 
VIN=12V 
VOUT=5V 
MAX=7A 
OCP=10A 
FS=250kHz 
5V SWITCHING TPS53319 
Switching Frequency 
Adjustment 
DVT 
20120719 
DVT 
20120712 
DVT 
20120724 
Vout=0.6x(1+Ru/Rd) 
=4.992V 
P5VB_VBST_NET 
P5VB_MODE_PG 
P5VB_VBST 
P5VB_VFB_NET 
P5VB_SNB 
P5VB_VFB 
P5VB_TRIP 
P5VB_VDD 
P5VB_12VIN 
P5VB_EN 
P5VB_ROVP 
P5VB_RF 
P5VB_LL 
P5VB_MODE 
P5VB_PGD 
P5VB_LL_NET 
P5VB 
P12V 
P5VB_VREG 
P5VB_AGND 
P5VB_AGND 
P5VB_VREG 
P5VB_AGND 
P5VB 
P5VB_AGND 
Title 
Size Document Number Rev 
Date: Sheet 
of 
KNOX_DPB 1A 
P5VB FOR HDD 5-9 
A3 
17 21 Thursday, October 11, 2012 
Wiwynn 
H/W R&D Dept. II 
8F,90,Sec. 1,Hsin Tai Wu Rd, 
Hsichih, Taipei Hsien 221, Taiwan, R.O.C 
Title 
Size Document Number Rev 
Date: Sheet 
of 
KNOX_DPB 1A 
P5VB FOR HDD 5-9 
A3 
17 21 Thursday, October 11, 2012 
Wiwynn 
H/W R&D Dept. II 
8F,90,Sec. 1,Hsin Tai Wu Rd, 
Hsichih, Taipei Hsien 221, Taiwan, R.O.C 
Title 
Size Document Number Rev 
Date: Sheet 
of 
KNOX_DPB 1A 
P5VB FOR HDD 5-9 
A3 
17 21 Thursday, October 11, 2012 
Wiwynn 
H/W R&D Dept. II 
8F,90,Sec. 1,Hsin Tai Wu Rd, 
Hsichih, Taipei Hsien 221, Taiwan, R.O.C 
TP20 TPAD32-GP TP20 TPAD32-GP 1
PC21 
SCD1U25V2KX-GP 
PC21 
SCD1U25V2KX-GP 
1 2PR50 
10KR2F-2-GP 
PR50 
10KR2F-2-GP 
1 2
PR29 
73K2R2F-GP 
PR29 
73K2R2F-GP 
1 2
PG2 
COPPER-CLOSE-GP-U 
PG2 
COPPER-CLOSE-GP-U 
1 2
PR22 
866KR2F-GP 
DY PR22 
866KR2F-GP 
DY 
1 2
PC24 
SC22U25V5MX-GP 
PC24 
SC22U25V5MX-GP 
1 2
PR28 
0R2J-2-GP 
PR28 
0R2J-2-GP 
1 2
PC16 
SC22U25V5MX-GP 
PC16 
SC22U25V5MX-GP 
1 2
PL3 
BLM41PG600-GP 
PL3 
BLM41PG600-GP 
1 2
PR26 
100KR2F-L1-GP 
PR26 
100KR2F-L1-GP 
1 2
PC17 
SC1U10V2KX-1GP 
PC17 
SC1U10V2KX-1GP 
1 2
PR17 
2K49R2F-GP 
PR17 
2K49R2F-GP 
1 2
PR24 
0R3J-0-U-GP 
PR24 
0R3J-0-U-GP 
1 2
PTC3 
ST330U10VDM-2GP 
PTC3 
ST330U10VDM-2GP 
1 2
PR25 
10KR2F-2-GP 
PR25 
10KR2F-2-GP 
1 2
PC25 
SC10U16V6KX-2GP 
PC25 
SC10U16V6KX-2GP 
1 2
PR31 
76K8R2F-GP 
PR31 
76K8R2F-GP 12TP23 
TPAD32-GP 
TP23 
TPAD32-GP 
1
PR18 
0R2J-2-GP 
PR18 
0R2J-2-GP 
1 2
PR21 
10R2F-L-GP 
PR21 
10R2F-L-GP 
1 2
PC19 
SC1KP50V2KX-1GP 
PC19 
SC1KP50V2KX-1GP 
1 2
PR19 
0R3J-0-U-GP 
PR19 
0R3J-0-U-GP 
1 2
PC18 
SC22U25V5MX-GP 
PC18 
SC22U25V5MX-GP 
1 2
PC26 
SC10U16V6KX-2GP 
PC26 
SC10U16V6KX-2GP 
1 2
PC14 
SC22U25V5MX-GP 
PC14 
SC22U25V5MX-GP 
1 2
PU2 
TPS53319DQPR-GP 
PU2 
TPS53319DQPR-GP 
VFB 1PGOOD 3
EN 2
VBST 4
ROVP 5
LL#6 6
LL#7 7
LL#8 8
LL#9 9
LL#10 10 
LL#11 11 
VIN 12 VIN 13 VIN 14 VIN 15 VIN 16 VIN 17 
VREG 18 
VDD 19 
MODE 20 
TRIP 21 
RF 22 
GND 23 
PC22 
SC22U25V5MX-GP 
PC22 
SC22U25V5MX-GP 
1 2
PR27 
10KR2D-GP 
PR27 
10KR2D-GP 
1 2
PR23 
10KR2F-2-GP 
PR23 
10KR2F-2-GP 
1 2
PTC4 
ST330U10VDM-2GP 
PTC4 
ST330U10VDM-2GP 
1 2
PR30 
115KR2F-GP 
PR30 
115KR2F-GP 
1 2
PR20 
3D01R2F-GP 
DY PR20 
3D01R2F-GP 
DY 
12
PC20 
SC2200P50V2KX-2GP 
DY PC20 
SC2200P50V2KX-2GP 
DY 
1 2
PR32 
10KR2D-GP 
PR32 
10KR2D-GP 
1 2
PL4 
IND-4D7UH-291-GP 
PL4 
IND-4D7UH-291-GP 
1 2
PC23 
SC4D7U25V5KX-GP 
PC23 
SC4D7U25V5KX-GP 
1 2
PC15 
SCD1U25V2KX-GP 
PC15 
SCD1U25V2KX-GP 
1 2



5
5
4
4
3
3
2
2
1
1
D D
C C
B B
A A
Vishay 4.7uH 
DCR=15m ohm,Irate =10A,Isat=24A 
13.2*12.9*3.5 mm3 
VIN=12V 
VOUT=5V 
MAX=7A 
OCP=10A 
FS=250kHz 
5V SWITCHING TPS53319 
Switching Frequency 
Adjustment 
DVT 
20120719 
DVT 
20120712 DVT 
20120724 
Vout=0.6x(1+Ru/Rd) 
=4.992V 
P5VC_VBST_NET 
P5VC_PGD 
P5VC_MODE_PG 
P5VC_VBST 
P5VC_VFB_NET 
P5VC_LL_NET 
P5VC_SNB 
P5VC_VFB 
P5VC_TRIP 
P5VC_12VIN 
P5VC_VDD 
P5VC_EN 
P5VC_ROVP 
P5VC_LL 
P5VC_RF 
P5VC_MODE 
P5VC 
P12V 
P5VC_VREG 
P5VC_AGND 
P5VC_AGND 
P5VC_VREG 
P5VC_AGND 
P5VC 
P5VC_AGND 
Title 
Size Document Number Rev 
Date: Sheet 
of 
KNOX_DPB 1A 
P5VC FOR HDD 10-14 
A3 
18 21 Thursday, October 11, 2012 
Wiwynn 
H/W R&D Dept. II 
8F,90,Sec. 1,Hsin Tai Wu Rd, 
Hsichih, Taipei Hsien 221, Taiwan, R.O.C 
Title 
Size Document Number Rev 
Date: Sheet 
of 
KNOX_DPB 1A 
P5VC FOR HDD 10-14 
A3 
18 21 Thursday, October 11, 2012 
Wiwynn 
H/W R&D Dept. II 
8F,90,Sec. 1,Hsin Tai Wu Rd, 
Hsichih, Taipei Hsien 221, Taiwan, R.O.C 
Title 
Size Document Number Rev 
Date: Sheet 
of 
KNOX_DPB 1A 
P5VC FOR HDD 10-14 
A3 
18 21 Thursday, October 11, 2012 
Wiwynn 
H/W R&D Dept. II 
8F,90,Sec. 1,Hsin Tai Wu Rd, 
Hsichih, Taipei Hsien 221, Taiwan, R.O.C 
TP21 TPAD32-GP TP21 TPAD32-GP 1
PC34 
SCD1U25V2KX-GP 
PC34 
SCD1U25V2KX-GP 
1 2
PR45 
73K2R2F-GP 
PR45 
73K2R2F-GP 
1 2
PG3 
COPPER-CLOSE-GP-U 
PG3 
COPPER-CLOSE-GP-U 
1 2
PR38 
866KR2F-GP 
DY PR38 
866KR2F-GP 
DY 
1 2
R487 
2K49R2F-GP 
R487 
2K49R2F-GP 
1 2
PL5 
BLM41PG600-GP 
PL5 
BLM41PG600-GP 
1 2
PR44 0R2J-2-GP PR44 0R2J-2-GP 
1 2
PTC6 
ST330U10VDM-2GP 
PTC6 
ST330U10VDM-2GP 
1 2
R486 
0R3J-0-U-GP 
R486 
0R3J-0-U-GP 
1 2
PR42 
100KR2F-L1-GP 
PR42 
100KR2F-L1-GP 
1 2
PR41 
10KR2F-2-GP 
PR41 
10KR2F-2-GP 
1 2
PR51 
10KR2F-2-GP 
PR51 
10KR2F-2-GP 
1 2
PC31 
SC22U25V5MX-GP 
PC31 
SC22U25V5MX-GP 
1 2
PC38 
SC10U16V6KX-2GP 
PC38 
SC10U16V6KX-2GP 
1 2
PC29 
SC22U25V5MX-GP 
PC29 
SC22U25V5MX-GP 
1 2
PR47 
76K8R2F-GP 
PR47 
76K8R2F-GP 12
PC30 
SC1U10V2KX-1GP 
PC30 
SC1U10V2KX-1GP 
1 2
PR34 
0R2J-2-GP 
PR34 
0R2J-2-GP 
1 2
PC35 
SC22U25V5MX-GP 
PC35 
SC22U25V5MX-GP 
1 2
PR35 
0R3J-0-U-GP 
PR35 
0R3J-0-U-GP 
1 2
PR37 
10R2F-L-GP 
PR37 
10R2F-L-GP 
1 2
PC32 
SC1KP50V2KX-1GP 
PC32 
SC1KP50V2KX-1GP 
1 2
PTC5 
ST330U10VDM-2GP 
PTC5 
ST330U10VDM-2GP 
1 2
PR43 
10KR2D-GP 
PR43 
10KR2D-GP 
1 2
PU3 
TPS53319DQPR-GP 
PU3 
TPS53319DQPR-GP 
VFB 1PGOOD 3
EN 2
VBST 4
ROVP 5
LL#6 6
LL#7 7
LL#8 8
LL#9 9
LL#10 10 
LL#11 11 
VIN 12 VIN 13 VIN 14 VIN 15 VIN 16 VIN 17 
VREG 18 
VDD 19 
MODE 20 
TRIP 21 
RF 22 
GND 23 
PR39 
10KR2F-2-GP 
PR39 
10KR2F-2-GP 1 2
PC33 
SC2200P50V2KX-2GP 
DY PC33 
SC2200P50V2KX-2GP 
DY 
1 2
PL6 
IND-4D7UH-291-GP 
PL6 
IND-4D7UH-291-GP 
1 2
PR36 
3D01R2F-GP 
DY PR36 
3D01R2F-GP 
DY 
12
PC37 
SC22U25V5MX-GP 
PC37 
SC22U25V5MX-GP 
1 2
PR48 
10KR2D-GP 
PR48 
10KR2D-GP 1 2
PR46 
115KR2F-GP 
PR46 
115KR2F-GP 
1 2
PC39 
SC10U16V6KX-2GP 
PC39 
SC10U16V6KX-2GP 
1 2
PC27 
SC22U25V5MX-GP 
PC27 
SC22U25V5MX-GP 
1 2
PC28 
SCD1U25V2KX-GP 
PC28 
SCD1U25V2KX-GP 
1 2
TP24 
TPAD32-GP 
TP24 
TPAD32-GP 
1
PC36 
SC4D7U25V5KX-GP 
PC36 
SC4D7U25V5KX-GP 
1 2



5
5
4
4
3
3
2
2
1
1
D D
C C
B B
A A
DVT 
20120626 
Remove H1 
DVT 
20120626 
Remove H10 
DVT 
20120720 
Remove H13 
PVT 
20121008 
Title 
Size Document Number Rev 
Date: Sheet 
of 
KNOX_DPB -1 
SCREWS 
A3 
19 21 Thursday, October 11, 2012 
Wiwynn 
H/W R&D Dept. II 
8F,90,Sec. 1,Hsin Tai Wu Rd, 
Hsichih, Taipei Hsien 221, Taiwan, R.O.C 
Title 
Size Document Number Rev 
Date: Sheet 
of 
KNOX_DPB -1 
SCREWS 
A3 
19 21 Thursday, October 11, 2012 
Wiwynn 
H/W R&D Dept. II 
8F,90,Sec. 1,Hsin Tai Wu Rd, 
Hsichih, Taipei Hsien 221, Taiwan, R.O.C 
Title 
Size Document Number Rev 
Date: Sheet 
of 
KNOX_DPB -1 
SCREWS 
A3 
19 21 Thursday, October 11, 2012 
Wiwynn 
H/W R&D Dept. II 
8F,90,Sec. 1,Hsin Tai Wu Rd, 
Hsichih, Taipei Hsien 221, Taiwan, R.O.C 
H9 
HOLE 
H9 
HOLE 
1
H8 
HOLE 
H8 
HOLE 
1
H7 
HOLE 
H7 
HOLE 
1
H4 
HOLE 
H4 
HOLE 
1
H6 
HOLE 
H6 
HOLE 
1
H11 
HOLE 
H11 
HOLE 
1
H16 
HOLE 
H16 
HOLE 
1
H2 
HOLE 
H2 
HOLE 
1
H15 
HOLE 
H15 
HOLE 
1
H5 
HOLE 
H5 
HOLE 
1
H12 
HOLE 
H12 
HOLE 
1
H14 
HOLE 
H14 
HOLE 
1
H3 
HOLE 
H3 
HOLE 
1



5
5
4
4
3
3
2
2
1
1
D D
C C
B B
A A
2012/03/12 
1. Change SAS2x28_A_HDD15_TX_+/- to PIN.B78/B79, sheet 12. 
2012/03/14 
1. HDD LED behavior change 
   Blue LED is for healthy status, it is reverse from fault, seet 3-10. 
V04: (<name>) 
2012/03/05 
2012/02/28 3rd schematic review 
V03: (<name>) 
1. Add 12 to 5V solutions, sheet 16-18. 
2. Add P12V to P3V3 solution(LDO to Buck), sheet 15. 
2012/03/27 
1. Re-order RX diff pairs of HDD 15, 6, 5, 10, 11 and 12, for SEB_B, sheet 12. 
EVT-1_V05: (<name>) 
EVT-2_V01: (<name>) (BOM modified) 
2012/04/25 
1. Corrected the net name for 12V, 5VA, B and C sense voltage, sheet 11. 
2. Modified EXP ID setting pull down resistance R358 from 10K to 100 ohm, sheet 12. 
3. Change all  HDD FLT, PWR signals pull up resistances from dummy to 100K ohm, sheet 3~10. 
4. Use wire jump to add HDD3 PWR pull up resistance R436, sheet 4. 
5. Use wire jump to add HDD13 FLT pull up resistance R505 & R506, sheet 9. 
EVT-3_V01: (<name>) 04/12 Gerber released 
2012/04/12 
1. Added map of Hdd PRSNT signal connect to EXP CONN, sheet 14. 
2. Modified CN5.CN6 PWR pin name to map HDD PWR signals, sheet 14 
3. Modified CN1.CN2 FLT pin name to map HDD FLT signals, sheet 12. 
4. Reverse pulling out detection LED16 pin (layout modified), sheet 13. 
EVT-3R_V01: (<name>) (Only BOM Change) 
2012/06/20 
1. Fine tune voltage offset and fix without SEB to cause I2C_C floating issue 
   a.) Dummy 4.7K ohm pull up resistors on location R342.and R344 beyond buffer, sheet 11. 
   b.) Mount 10K ohm pull up resistors on location R369 and R370 before buffer, sheet 15. 
2. Modifed 0 ohm  PR54 symbol, because of sourcer strategy, it's still 0 ohm and just for 
   different Wiwynn P/N, sheet 15. 
3. Fix HDD 12V can't turn off issue, sheet 3-10. 
   a.) Modify dual BJT to MOSFETon location Q1.Q4.Q6.Q8.Q10.Q12.Q14.Q16.Q18.Q20.Q22.Q24.Q26.Q28.Q30. 
   b.) Modify MOSFET gate resistor from 1K to 0 ohm on location R112.R126.R140.R153.R168.R182.R196. 
       R210.R224.R238.R252.R266.R280.R294.R308. 
4. Add Revision control on page 1. 
5. Mount 100K PU R on location R436 for HDD3 PWR control, sheet 4. 
6. Mount 100K PR R on location R505 and R506 for HDD13 FLT, sheet 9. 
DVT_V01: (<name>) 
2012/07/01 
1. Move "Pulling out detection", "PWR&FFC CONN", "I2C_C buffers and PU R" to PTB 
    a.) Pulling out detection, sheet 13. 
        Remove: Q31, Q32, Q33, LED16, R366, R363, R478, R374, R375, R376, R377, R378, R365. 
    b.) PWR and FFC CONN, sheet 14. 
        Remove: CN3 (FFC), CN4 (4P PWR) 
                R384, R385, TC3, TC4, TC5, C355. 
    c.) I2_C buffers, sheet 11. 
        Remove: U51 (PCA9525), U55 (PCA9507) 
                R342, R343, R344, R353, R479, R480, R481. 
                C344, C345, C356, C364, C365, C366. 
    d.) I2C_C PU, sheet 15. 
        Remove: R369, R370. 
2. Add LED power control circuits for each HDD0 to 14, sheet 3~10. 
    a.) Remove reserved LED 3.3V supply voltage, R393 to R407. 
    b.) Add BJT base R 1K ohm: R343, R353, R365, R369, R374, R376, R378, R384, R393, R394, R396, R398, 
        R400, R402, R404. 
    c.) Add BJT collect R 10K ohm : R342, R344, R363, R366, R370, R375, R377, R383, R385, R395, R397, 
        R399, R401, R403, R405 
    d.) Add NPN BJT, Q49, Q50, Q51, Q53, Q55, Q57, Q59, Q61, Q63, Q65, Q67, Q69, Q71, Q73, Q75. 
    e.) Add N-channel MOSFET, Q31, Q32, Q33, Q52, Q54, Q56, Q58, Q60, Q62, Q64, Q66, Q68, Q70, Q72, Q74. 
3. Add 0 ohm on gate of MOSFET for HDD 12V power OFF control, sheet 3~10. 
   Add R408~R421, R480 for each HDD. 
4. Swap AND gate U21 input signals, sheet 6. 
   connect SAS_EXP_A_PWR6 to A of U21_Pin 2. 
   connect SAS_EXP_B_PWR6 to B of U21_Pin 1. 
5. Have more design margin on cap voltage rating, change C251 from 10uF/6.3V to 10uF/16V, sheet 7. 
6. Add GPIO control signals, sheet 12 and 14. 
     a.) Add "FCB_HW_REV" on CN1_B2, CN2_B2 and CN7_S17. 
     b.) Add net "Tray ID" on CN1_A12, CN2_A12 and CN7_S15. 
     c.) Add net "DPB_HW_REV" on CN1_B11, CN2_B11. 
         Mount PD 100 ohm R407. 
         Dummy PU 10K ohm R406. 
     d.) Add net "SD_LATCH_RELEASE" on CN1_A41, CN2_A41 and CN7_S18. 
     e.) Add net "PEER_1A&2A_HB" on CN1_B60, CN2_B60 and CN7_S20. 
     f.) Add net "PEER_1B&2B_HB" on CN1_A79, CN2_A79 and CN7_S21. 
7. Add SAS interconnection, sheet 12. 
    a.) connect SEB_AB_TX to SEB_AB_RX via 0.01uF C38 and C39. 
    b.) connect SEB_BA_TX to SEB_BA_RX via 0.01uF C36 and C37. 
8. Add reserved 0 ohm damping R on location R481, R507, R508, R509, R510, R511 for I2C_B, C and D bus 
   for over/under shot improvement, 
9. Add straddle tyep power edge CONN CN7, sheet14. 
10.Net name correction, Sheet 12 and 13. 
    a.) Change HB_EXP_A_OUT to SELF_1A&2A_HB. 
    b.) Change HB_EXP_B_OUT to SELF_1B&2B_HB. 
    c.) Change temp_sensor_A_ADDR0/ID to TEMP_SENSOR_A_ADDR0&ID. 
    d.) Change temp_sensor_B_ADDR0/ID to TEMP_SENSOR_B_ADDR0&ID 
    e.) Change SAS2x28_A_HDD15_TX+ to SEB_AB_TX+ 
    f.) Change SAS2x28_A_HDD15_TX- to SEB_AB_TX- 
    g.) Change SAS2x28_A_HDD15_RX+ to SEB_BA_RX+ 
    h.) Change SAS2x28_A_HDD15_RX- to SEB_BA_RX- 
    i.) Change SAS2x28_B_HDD15_TX+ to SEB_BA_TX+ 
    j.) Change SAS2x28_B_HDD15_TX- to SEB_BA_TX- 
    k.) Change SAS2x28_B_HDD15_RX+ to SEB_AB_RX+ 
    l.) Change SAS2x28_B_HDD15_RX- to SEB_AB_RX- 
    m.) Change Tray present_OUT to SELF_TRAY_PRESENT 
    o.) Change Tray present_IN to PEER_TRAY_PRESENT 
11.Add 0 ohm for 3.3V switching power measurement, sheet 15. 
    a.) Add 0603 0 ohm PR63, 0805 0 ohm PR57 for line/load regulation measurement. 
    b.) move PR54 above PR55 for phase/gain margin measurement. 
12.connect EXP_A_PRNST_TX and EXP_B_PRNST_TX to "OR gate" U52 inputs, output "SEB_DETECT" to CN7_S22. 
2012/07/03 
1. Change N-channel single MOSFET to dual on location Q31, Q32, Q33, Q52, Q54, Q56, Q58, Q60, 
    Q62, Q64, Q66, Q68, Q70, Q72, Q74, sheet 3-10. 
2. Change RED LED supply voltage to 3.3V also change the current limiation R from 510 to 330 ohm 
   on location R104, R117, R131, R145, R159, R173, R187, R201 ,R215, R229, R243, R257, R271, 
   R285, R299, sheet 3-10. 
3. Remove SEB_DETECT function, delete U52, sheet 14. 
4. Change cap of each AND gate supply voltage from 10uF to 0.1uF and dummy another 1uF caps sheet 
   3-10. 
     a.) change folloiwng caps from 10uF to 0.1uF. 
         C102, C11, C117, C125, C133, C141, C149, C158, C165, C171, C181, C187, C197, C203, C213, 
         C219, C229, C235, C245, C253, C261, C269, C277, C283, C293, C301, C309, C315, C324, C339. 
      b.) dummy following 1uF caps. 
          C101, C109, C116, C124, C132, C140, C148, C157, C164, C170, C180, C186, C196, C202, C212, 
          C218, C228, C234, C244, C252, C260, C268, C276, C282, C292, C300, C308, C314, C325, C337. 
2012/07/04 
1. Reserve 0 ohm resistor for 12V and 5V PTC, sheet 3-10. 
     a.) Add 0 ohm R with 1206 package R512, R513, R517, R519, R521, R523, R525, R527, R529, R531, R533, 
         R535, R537, R539, R541 for 12V. 
     b.) Add 0 ohm R with 0805 package R514, R515, R516, R518, R520, R522, R524, R526, R528, R530, 
         R532, R534, R536, R538, R540 for 5V. 
2012/07/05 
1. CN7 Pin definition modification 
    a.) Change S24 from GND to 5VA, it is to reserve 5V supply for pulling out detector LED. 
    b.) Change P9 and P28 from 12.5V to GND for layout pad consideration. 
Title 
Size Document Number Rev 
Date: Sheet 
of 
KNOX_DPB -1 
CHANGE HISTORY_1 
C
20 21 Thursday, October 11, 2012 
Wiwynn 
H/W R&D Dept. II 
8F,90,Sec. 1,Hsin Tai Wu Rd, 
Hsichih, Taipei Hsien 221, Taiwan, R.O.C 
Title 
Size Document Number Rev 
Date: Sheet 
of 
KNOX_DPB -1 
CHANGE HISTORY_1 
C
20 21 Thursday, October 11, 2012 
Wiwynn 
H/W R&D Dept. II 
8F,90,Sec. 1,Hsin Tai Wu Rd, 
Hsichih, Taipei Hsien 221, Taiwan, R.O.C 
Title 
Size Document Number Rev 
Date: Sheet 
of 
KNOX_DPB -1 
CHANGE HISTORY_1 
C
20 21 Thursday, October 11, 2012 
Wiwynn 
H/W R&D Dept. II 
8F,90,Sec. 1,Hsin Tai Wu Rd, 
Hsichih, Taipei Hsien 221, Taiwan, R.O.C 



5
5
4
4
3
3
2
2
1
1
D D
C C
B B
A A
DVT_V02: (<name>) 
2012/07/08 
1. change R389 to 2K to enlarge the voltage after divider from 1.09V to 2V, sheet 11. 
2. Add change note for interconnection SAS pairs, sheet 12.    
   SEB_AB_TX+, SEB_AB_TX-, SEB_BA_RX+, SEB_BA_RX-, SEB_BA_TX+,SEB_BA_TX-,SEB_AB_RX+, SEB_AB_RX- 
3. Add change note for "FCB_HW_REV" and correct the note for CN2, sheet 12. 
4. Change the off-page symbol for signal PWM_EXP_B and PWM_EXP_A from output to input type, sheet 14. 
5. Reserve 0 ohm resistor R542 and R543 with 1206 package for 12V to SEB, sheet 12. 
2012/07/10 
1. change R389 to 2K to enlarge the voltage after divider from 1.09V to 2V, sheet 11. 
2. Add change note for interconnection SAS pairs, sheet 12.    
   SEB_AB_TX+, SEB_AB_TX-, SEB_BA_RX+, SEB_BA_RX-, SEB_BA_TX+,SEB_BA_TX-,SEB_AB_RX+, SEB_AB_RX- 
3. Add change note for "FCB_HW_REV" and correct the note for CN2, sheet 12. 
4. Change the off-page symbol for signal PWM_EXP_B and PWM_EXP_A from output to input type, sheet 14. 
5. Reserve 0 ohm resistor R542 and R543 with 1206 package for 12V to SEB, sheet 12. 
6. Remove reserved 1uF cap for each AND supply power, sheet 3-10. 
   C101, C109, C116, C124, C132, C140, C148, C157, C164, C170, C180, C186, C196, C202, C212, 
   C218, C228, C234, C244, C252, C260, C268, C276, C282, C292, C300, C308, C314, C325, C337. 
7. LED power control circuitry correct, sheet 3-10.
   a.) Change K ohm R343, R353, R365, R369, R374, R376, R378, R384, R393, R394, R396, R398, 
       R400, R402, R404 to 0 ohm 
   b.) Change BJT to MOSFET on locations Q49, Q50, Q51, Q53, Q55, Q57, Q59, Q61, Q63, Q65, 
        Q67, Q69, Q71, Q73, Q75. 
8. Depopulate 12V and 5V PTC, populate 0 ohm, sheet 3-10. 
    a.) Mount 0 ohm R with 1206 package on locations R512, R513, R517, R519, R521, R523, R525, R527, 
        R529, R531, R533, R535, R537, R539, R541 for 12V. 
    b.) Mount 0 ohm R with 0805 package on locations R514, R515, R516, R518, R520, R522, R524, R526, 
        R528, R530, R532, R534, R536, R538, R540 for 5V. 
    c.) Depopulate PTC F1 to F30 . 
9. Change all caps 12votls from 16V to 25V rating to have more margin, sheet 3-10, 14, 16-18. 
    a.) change from 10uF/16V to 10uF/25V on locations 
        C111-C114, C126-C129, C142-C145, C159-C162, C174-C177, C191-C194, C207-C210, C223-C226, C239-C242, 
        C255-C258, C271, C273-C275, C287-C290, C302-C306, C318-C321, C333-C336, C348, C349, total 62 pcs. 
    b.) Change from 1uF/16V to 1uF/25V on locations
        C115, C130, C146, C163, C179, C195, C211, C227, C243, C259, C272, C291, C307, C322, C338, total 15 pcs 
    c.) Change from 22uF/16V to 22uF/25V on locations 
        PC1-PC5, PC14, PC16, PC18, PC22, PC24, PC27, PC29, PC31, PC35, PC37, total 15 pcs. 
10.Add addition damping resistors R544, R545, R546, R547, R548 and R549 for I2C_B, C and D bus to reduce the lenght. 
DVT_V03: (<name>) 
2012/07/12 
1. Change to value of PU R on AND input from 100K to 4.7K ohm to increase the sink current of gate, sheet 3-10. 
   Change: R422-R477, R494-R495, R055-R506, total 60 pcs. 
2. Bypass PTC with 0 ohm R for 12V to SEB, sheet 12. 
   Depopulate F31, F32, Populate R542, R543. 
3. Change the voltage rating of 330uF POS cap, PTC1-PTC6 from 6.3V to 10V for 5V power rail, sheet 16-18. 
2012/07/20 
1. Remove screw hole H13 to accomodate with ME drawing, sheet 19. 
2012/07/24 (BOM change only) 
1. Simplify material type and use one rating sheet 11, 16, 17 and 18. 
    a.) Change PR49, PR50 and PR51 from 10K J tolerance to 10K F tolerane. 
    b.) Change R381, R364 from 4.7K F to J tolerance, the same as other 4.7K parts. 
    c.) Change PC41  0.1U 16V K0402 to non-limited P/N, only P/N changed. 
    d.) Change C107 C123 C139 C155 C173 C189 C206 C221 C237 C251 C267 C285 C299 C317 
        C331 from 10U 16V Z1206 Y5V to 10U 16V K1206 X7R. 
    e.) Change PC42 to non-limited P/N, only P/N changed. 
2. Due to the output current is small for 3.3V switching power, 
   change PL7 from 68uH to 22uH to prevent double pulses issue as happened on FCB. 
PVT_V01: (<name>) 
2012/10/08 
1. Change the diameter of H11 the same as H5, sheet 19. 
PVT_V02: (<name>) 
2012/10/09 
1. change 0805 size for HDD 5V PTC bypass 
   R514, R515, R516, R518, R520, R522, R524, R526, R528, R530, R532, R534, R536, R538, R540, 
   total 15 pcs to "gap close". 
2. Suggest to change 1206 size for HDD 12V and SEB PTC bypass 
   R512, R513, R517, R519, R521, R523, R525, R527, R529, R531, R533, R535, R537,R539, R541, R542, R543, 
   total 17 pcs to "gap close". 
PVT_V03: (<name>) 
2012/10/11 
1. Changed reserve 0 ohm for power measurement to "gap close", sheet 15.  
   a.) Change 0603 size PR63 to "gap close". 
   b.) Change 0805 size PR57 to "gap close". 
Title 
Size Document Number Rev 
Date: Sheet 
of 
KNOX_DPB 1A 
CHANGE HISTORY_2 
C
21 21 Thursday, October 11, 2012 
Wiwynn 
H/W R&D Dept. II 
8F,90,Sec. 1,Hsin Tai Wu Rd, 
Hsichih, Taipei Hsien 221, Taiwan, R.O.C 
Title 
Size Document Number Rev 
Date: Sheet 
of 
KNOX_DPB 1A 
CHANGE HISTORY_2 
C
21 21 Thursday, October 11, 2012 
Wiwynn 
H/W R&D Dept. II 
8F,90,Sec. 1,Hsin Tai Wu Rd, 
Hsichih, Taipei Hsien 221, Taiwan, R.O.C 
Title 
Size Document Number Rev 
Date: Sheet 
of 
KNOX_DPB 1A 
CHANGE HISTORY_2 
C
21 21 Thursday, October 11, 2012 
Wiwynn 
H/W R&D Dept. II 
8F,90,Sec. 1,Hsin Tai Wu Rd, 
Hsichih, Taipei Hsien 221, Taiwan, R.O.C 